%FSTAX23Y23*%
%MOIN*%
%SFA1B1*%

%IPPOS*%
%ADD13C,0.010000*%
%ADD17C,0.006000*%
%ADD19C,0.008000*%
%ADD21C,0.005000*%
%ADD24C,0.009000*%
%ADD26O,0.078740X0.023620*%
%ADD27R,0.039370X0.074800*%
%ADD28R,0.070870X0.074800*%
%ADD29R,0.055910X0.061020*%
%ADD30R,0.017720X0.054330*%
%ADD31R,0.064960X0.051180*%
%ADD32R,0.078740X0.098430*%
%ADD33R,0.019680X0.090550*%
%ADD34R,0.041340X0.039370*%
%ADD35R,0.086610X0.041340*%
%ADD36R,0.019680X0.035430*%
%ADD37O,0.057090X0.017720*%
%ADD38R,0.077560X0.022440*%
%ADD39R,0.025590X0.041340*%
%ADD40R,0.051180X0.074800*%
%ADD41R,0.039370X0.070870*%
%ADD42R,0.039370X0.090550*%
%ADD43R,0.041340X0.045280*%
%ADD44R,0.027560X0.045280*%
%ADD45R,0.053150X0.027560*%
%ADD46R,0.050000X0.200000*%
%ADD47R,0.057090X0.037400*%
%ADD48R,0.028350X0.039370*%
%ADD49R,0.025590X0.023620*%
%ADD50R,0.028000X0.165000*%
%ADD51R,0.028000X0.126000*%
%ADD52R,0.031500X0.066930*%
%ADD53R,0.070870X0.009840*%
%ADD54R,0.026570X0.009840*%
%ADD55R,0.009840X0.022640*%
%ADD56R,0.027560X0.035430*%
%ADD57R,0.038580X0.034250*%
%ADD58R,0.212600X0.114170*%
%ADD59R,0.165350X0.125980*%
%ADD60R,0.096460X0.124020*%
%ADD61R,0.033470X0.039370*%
%ADD62R,0.057090X0.045280*%
%ADD63R,0.037400X0.039370*%
%ADD64R,0.025200X0.026770*%
%ADD65R,0.010830X0.009840*%
%ADD66R,0.009840X0.010830*%
%ADD67R,0.061020X0.009840*%
%ADD68R,0.066930X0.053150*%
%ADD69R,0.009840X0.061020*%
%ADD70R,0.053150X0.066930*%
%ADD71R,0.045280X0.057090*%
%ADD72R,0.026770X0.025200*%
%ADD73R,0.039370X0.037400*%
%ADD74R,0.039370X0.033470*%
%ADD75R,0.039370X0.028350*%
%ADD76R,0.023620X0.025590*%
%ADD77R,0.082870X0.044090*%
%ADD78R,0.035430X0.027560*%
%ADD143C,0.120000*%
%ADD150C,0.250000*%
%ADD153C,0.020000*%
%ADD154C,0.016000*%
%ADD155R,0.110430X0.066930*%
%ADD156R,0.105320X0.067910*%
%ADD157C,0.031500*%
%ADD158C,0.065980*%
%ADD159C,0.061020*%
%ADD160R,0.061020X0.061020*%
%ADD161C,0.075000*%
%ADD162C,0.098430*%
%ADD163O,0.088580X0.177170*%
%ADD164O,0.177170X0.088580*%
%ADD165O,0.196850X0.098430*%
%ADD166C,0.112000*%
%ADD167C,0.021660*%
%ADD168C,0.055000*%
%ADD169R,0.055000X0.055000*%
%ADD170C,0.050000*%
%ADD171C,0.016000*%
%ADD172C,0.200000*%
%LNgrandmaster-1*%
%LPD*%
G36*
X07001Y035D02*
X0647D01*
Y03893*
X07001*
Y035*
G37*
G36*
X0462Y03246D02*
Y02826D01*
X04502Y02708*
X04355*
X04354Y02709*
X04353Y02713*
X04356Y02718*
X04358Y02725*
Y02749*
X04376*
Y02811*
X04303*
Y02749*
X04321*
Y02725*
X04322Y02718*
X04326Y02713*
X04325Y02709*
X04324Y02708*
X0425*
X04249Y02709*
X04248Y02713*
X04251Y02718*
X04253Y02725*
Y02749*
X04271*
Y02811*
X04212*
X0421Y02816*
X04214Y0282*
X04222*
X04223Y0282*
X04271*
Y02833*
X04303*
Y0282*
X04376*
Y02833*
X04384*
X04388Y02829*
X04394Y02825*
X04401Y02823*
X04404*
X04407Y0282*
Y02817*
Y02812*
Y02764*
X04462*
Y02771*
X04503*
X0451Y02772*
X04516Y02776*
X0452Y02782*
X04522Y02789*
X0452Y02796*
X04516Y02802*
X0451Y02806*
X04503Y02808*
X04465*
X04462Y02811*
Y02815*
Y0282*
Y02867*
X04407*
X04402Y02865*
X04398Y02868*
X04391Y02869*
X04376*
Y02882*
X04303*
Y02869*
X04271*
Y02882*
X04198*
Y02854*
X04193Y02851*
X04174Y02833*
X0417Y02827*
X04169Y0282*
Y02815*
X04122*
Y02764*
X04177*
Y02771*
X04183Y02773*
X04189Y02777*
X04193Y02781*
X04198Y02779*
Y02749*
X04216*
Y02725*
X04217Y02718*
X04221Y02713*
X0422Y02709*
X04219Y02708*
X0408*
X04078Y02713*
X04079Y02715*
X04081Y02722*
X04079Y02728*
X04078Y02731*
Y02749*
X04101*
Y02811*
X04028*
Y02749*
X04051*
Y02731*
X04049Y02728*
X04048Y02722*
X04049Y02715*
X04051Y02713*
X04048Y02708*
X03974*
X03973Y0271*
X03972Y02713*
X03975Y02717*
X03977Y02724*
X03975Y0273*
X03973Y02734*
Y02749*
X03996*
Y02811*
X03923*
Y02749*
X03946*
Y02731*
X03945Y0273*
X03944Y02724*
X03945Y02717*
X03948Y02713*
X03948Y0271*
X03946Y02708*
X036*
Y0287*
X03599Y02874*
X03597Y02878*
X03578Y02897*
X03574Y029*
X03569Y02901*
X03559*
Y02921*
Y02922*
Y02926*
Y02927*
Y02968*
Y0297*
Y02973*
Y02975*
Y02984*
X0356Y02985*
X03559Y02987*
Y03017*
X03509*
X03506Y03021*
Y03022*
Y03082*
X03497*
Y03087*
X03498Y03087*
X03503Y03091*
X03506Y03096*
X03508Y03103*
X03506Y03109*
X03503Y03114*
X03498Y03118*
X03491Y03119*
X03485Y03118*
X0348Y03114*
X03479Y03113*
X0331*
X03305Y03112*
X03301Y0311*
X03242Y0305*
X03239Y03047*
X03238Y03042*
Y02988*
X03218Y02968*
X03216Y02969*
X03214Y0297*
X03212Y02976*
X03209Y02981*
X03204Y02985*
X03197Y02986*
X03191Y02985*
X03186Y02981*
X03182Y02976*
X03181Y0297*
X03182Y02963*
X03186Y02958*
X03191Y02954*
X03197Y02953*
X03198Y02951*
X03199Y02948*
X03183Y02932*
X0318Y02928*
X03179Y02924*
Y02824*
X0318Y0282*
X03183Y02816*
X03191Y02807*
X03195Y02804*
Y02782*
X03222*
Y02831*
X03242*
Y02858*
X03241*
Y02875*
X03346Y0298*
X03351Y0298*
X03354Y02983*
X03409*
Y02975*
Y02973*
Y0297*
Y02968*
Y02927*
Y02926*
Y02922*
Y02921*
Y02901*
X03379*
X03377Y02903*
X0337Y02904*
X03364Y02903*
X03359Y02899*
X03355Y02894*
X03354Y02889*
X03292Y02827*
X03282*
Y02827*
X03255*
Y02798*
X03236*
Y02771*
X03261*
Y02782*
X03282*
Y02802*
X03297*
X03302Y02803*
X03306Y02806*
X03372Y02871*
X03377Y02872*
X03379Y02874*
X03409*
Y02861*
X03471*
Y02824*
X03455*
Y02769*
X03499*
Y02824*
X03498*
Y02861*
X03559*
Y02876*
X03564Y02876*
X03576Y02865*
Y02708*
X02827*
X02672Y02863*
Y03325*
X02898Y03551*
X04315*
X0462Y03246*
G37*
G36*
X06805Y02702D02*
X06352D01*
X06332Y02683*
Y02486*
X06116*
X0611Y02481*
X06106Y02482*
Y02771*
X0645*
X0646Y02781*
Y02968*
X06805*
Y02702*
G37*
G36*
X06942Y01511D02*
X06726Y01295D01*
X06663*
Y0159*
X06664*
Y01631*
X06663*
Y0165*
X06664*
Y01691*
X06663*
Y017*
X06664*
Y01741*
X06663*
Y01755*
X06664*
Y01788*
X06688Y01812*
X06692Y01812*
X06694Y01814*
X06705*
Y01788*
X06749*
Y01843*
X06753Y01846*
X06755*
X06759Y01843*
Y01788*
X06804*
Y01843*
X06808Y01846*
X0687*
X06874Y01843*
Y01788*
X06919*
Y01843*
X06923Y01846*
X06942*
Y01511*
G37*
%LNgrandmaster-2*%
%LPC*%
G36*
X069Y03647D02*
X06885Y03645D01*
X06871Y03639*
X06859Y0363*
X0685Y03618*
X06844Y03604*
X06842Y03589*
X06844Y03574*
X0685Y0356*
X06859Y03548*
X06871Y03539*
X06885Y03533*
X069Y03531*
X06915Y03533*
X06929Y03539*
X06941Y03548*
X0695Y0356*
X06955Y03574*
X06957Y03589*
X06955Y03604*
X0695Y03618*
X06941Y0363*
X06929Y03639*
X06915Y03645*
X069Y03647*
G37*
G36*
X06734D02*
X06719Y03645D01*
X06705Y03639*
X06694Y0363*
X06684Y03618*
X06679Y03604*
X06677Y03589*
X06679Y03574*
X06684Y0356*
X06694Y03548*
X06705Y03539*
X06719Y03533*
X06734Y03531*
X06749Y03533*
X06763Y03539*
X06775Y03548*
X06784Y0356*
X0679Y03574*
X06792Y03589*
X0679Y03604*
X06784Y03618*
X06775Y0363*
X06763Y03639*
X06749Y03645*
X06734Y03647*
G37*
G36*
X06569D02*
X06554Y03645D01*
X0654Y03639*
X06528Y0363*
X06519Y03618*
X06513Y03604*
X06511Y03589*
X06513Y03574*
X06519Y0356*
X06528Y03548*
X0654Y03539*
X06554Y03533*
X06569Y03531*
X06584Y03533*
X06598Y03539*
X0661Y03548*
X06619Y0356*
X06625Y03574*
X06627Y03589*
X06625Y03604*
X06619Y03618*
X0661Y0363*
X06598Y03639*
X06584Y03645*
X06569Y03647*
G37*
G36*
X03622Y03502D02*
X03616Y03501D01*
X03612Y03498*
X03566*
X03562Y03497*
X03558Y03494*
X03549Y03486*
X03544Y03488*
X03541Y03492*
X03536Y03496*
X03529Y03497*
X03523Y03496*
X03518Y03492*
X03514Y03487*
X03513Y03481*
X03514Y03474*
X03518Y03469*
X03522Y03466*
X03524Y03461*
X0351Y03446*
X03507Y03442*
X03506Y03438*
X03483*
X03482Y03439*
X03481Y03444*
X03484Y03449*
X03486Y03456*
X03484Y03462*
X03481Y03467*
X03476Y03471*
X03469Y03472*
X03463Y03471*
X03458Y03467*
X03456Y03464*
X03456Y03464*
X0345Y03465*
X03448Y03468*
X03443Y03472*
X03436Y03473*
X0343Y03472*
X03425Y03468*
X03424Y03468*
X03419Y03467*
X03411Y03475*
X03407Y03478*
X03403Y03479*
X03377*
X03373Y03478*
X03369Y03475*
X03357Y03464*
X03352Y03463*
X03348Y0346*
X03311*
X03306Y03465*
X03302Y03468*
X03297Y03468*
X03247*
X03242Y03468*
X03238Y03465*
X03126Y03353*
X03123Y03349*
X03122Y03344*
Y03307*
X03083*
X03075Y03305*
X03069Y03301*
X03065Y03294*
X03063Y03287*
X03065Y03279*
X03069Y03272*
X03075Y03268*
X03083Y03267*
X03138*
X03146Y03268*
X03153Y03272*
X03157Y03279*
X03158Y03287*
X03157Y03294*
X03153Y03301*
X03147Y03305*
Y03339*
X03252Y03444*
X03292*
X03297Y03439*
X03301Y03436*
X03305Y03435*
Y03362*
X03302Y0336*
X03296Y03359*
X03291Y03355*
X03287Y0335*
X03286Y03344*
X03287Y03337*
X03291Y03332*
X03296Y03328*
X03302Y03327*
X03309Y03328*
X03312Y03331*
X03317Y03329*
Y0331*
X03315Y03307*
X03314Y03301*
X03315Y03294*
X03319Y03289*
X03321Y03287*
X03321Y03287*
X0332Y03282*
X03265*
X03265Y03287*
X03266Y03288*
X03269Y03288*
X03275Y03292*
X03278Y03297*
X0328Y03303*
X03278Y0331*
X03275Y03315*
X03269Y03318*
X03263Y0332*
X03257Y03318*
X03252Y03315*
X03248Y0331*
X03247Y03303*
X03248Y03297*
X03252Y03292*
X03257Y03288*
X0326Y03288*
X03262Y03287*
X03261Y03282*
X03205*
X03201Y03281*
X03197Y03279*
X03167Y03249*
X03154*
X03153Y03251*
X03146Y03255*
X03138Y03257*
X03083*
X03075Y03255*
X03069Y03251*
X03065Y03244*
X03063Y03237*
X03065Y03229*
X03069Y03222*
X03075Y03218*
X03083Y03217*
X03138*
X03146Y03218*
X03153Y03222*
X03154Y03224*
X03172*
X03176Y03225*
X0318Y03228*
X0321Y03258*
X03328*
X03333Y03259*
X03337Y03262*
X03354Y03279*
X03359Y03276*
X03358Y03273*
X03359Y03266*
X03363Y03261*
X03368Y03257*
X03374Y03256*
X03381Y03257*
X03386Y03261*
X03389Y03266*
X03391Y03273*
X03389Y03279*
X03386Y03284*
X03381Y03288*
X03374Y03289*
X03371Y03288*
X03368Y03293*
X03393Y03318*
X03423Y03288*
X03427Y03285*
X03431Y03284*
X03481*
X03485Y03281*
X03491Y0328*
X03498Y03281*
X03503Y03285*
X03506Y0329*
X03508Y03297*
X03506Y03303*
X03503Y03308*
X03498Y03312*
X03491Y03313*
X03485Y03312*
X03481Y03309*
X03436*
X03405Y0334*
Y03351*
X03419*
X03423*
X03477*
X03478*
X03482*
X03483*
X03536*
X03537*
X03541Y03348*
Y03335*
X03536Y03334*
X03531Y0333*
X03527Y03325*
X03526Y03319*
X03527Y03312*
X03531Y03307*
X03536Y03303*
X03542Y03302*
X03549Y03303*
X03554Y03307*
X03557Y03312*
X03559Y03319*
X03557Y03325*
X03556Y03327*
X03559Y03332*
X03597*
Y03438*
X03543*
X03541Y03443*
X03571Y03473*
X03612*
X03616Y0347*
X03622Y03469*
X03629Y0347*
X03634Y03474*
X03637Y03479*
X03639Y03486*
X03637Y03492*
X03634Y03497*
X03629Y03501*
X03622Y03502*
G37*
G36*
X03068Y03411D02*
X03062Y0341D01*
X03057Y03407*
X03048*
X03044Y03406*
X0304Y03404*
X02835Y03199*
X028*
X02798Y03201*
X02792Y03205*
X02784Y03207*
X02729*
X02721Y03205*
X02715Y03201*
X0271Y03194*
X02709Y03187*
X0271Y03179*
X02715Y03172*
X02721Y03168*
X02729Y03167*
X02784*
X02792Y03168*
X02798Y03172*
X028Y03174*
X0284*
X02845Y03175*
X02849Y03178*
X03053Y03383*
X03058*
X03062Y0338*
X03068Y03379*
X03075Y0338*
X0308Y03384*
X03083Y03389*
X03085Y03395*
X03083Y03401*
X0308Y03407*
X03075Y0341*
X03068Y03411*
G37*
G36*
X03744Y03358D02*
X03738Y03357D01*
X03735Y03355*
X03715*
Y03357*
X03662*
Y03312*
X03657Y03308*
X03653Y03309*
X03647Y03308*
X03642Y03304*
X03638Y03299*
X03637Y03293*
X03638Y03286*
X03642Y03281*
X03647Y03277*
X03653Y03276*
X0366Y03277*
X03665Y03281*
X03668Y03286*
X0367Y03293*
X03669Y03296*
X03672Y03301*
X03715*
Y03328*
X03735*
X03738Y03326*
X03744Y03325*
X03751Y03326*
X03756Y0333*
X03759Y03335*
X03761Y03342*
X03759Y03348*
X03756Y03353*
X03751Y03357*
X03744Y03358*
G37*
G36*
X02784Y03307D02*
X02729D01*
X02721Y03305*
X02715Y03301*
X0271Y03294*
X02709Y03287*
X0271Y03279*
X02715Y03272*
X02721Y03268*
X02729Y03267*
X02784*
X02792Y03268*
X02798Y03272*
X02803Y03279*
X02804Y03287*
X02803Y03294*
X02798Y03301*
X02792Y03305*
X02784Y03307*
G37*
G36*
X03482Y03249D02*
X03478D01*
X03477*
X03424*
X03423*
X03419*
X03418*
X03365*
X03364*
X0336*
X03359*
X03305*
Y0318*
X03282Y03156*
X03281Y03156*
X03275Y03158*
X03269Y03156*
X03264Y03153*
X0326Y03147*
X03259Y03141*
X0326Y03135*
X03264Y0313*
X03269Y03126*
X03275Y03125*
X03281Y03126*
X03287Y0313*
X03287Y03131*
X0329Y03131*
X03294Y03134*
X03322Y03162*
X03359*
X0336*
X03364*
X03365*
X03418*
X03419*
X03423*
X03424*
X03477*
X03478*
X03482*
X03483*
X03537*
Y03249*
X03483*
X03482*
G37*
G36*
X03744Y03277D02*
X03738Y03276D01*
X03733Y03272*
X03729Y03267*
X03728Y03261*
X03729Y03254*
X03733Y03249*
X03738Y03245*
X03744Y03244*
X03751Y03245*
X03756Y03249*
X03759Y03254*
X03761Y03261*
X03759Y03267*
X03756Y03272*
X03751Y03276*
X03744Y03277*
G37*
G36*
X0323Y03251D02*
X03224Y0325D01*
X03219Y03246*
X03215Y03241*
X03214Y03235*
X03215Y03228*
X03219Y03223*
X03224Y03219*
X0323Y03218*
X03237Y03219*
X03242Y03223*
X03245Y03228*
X03247Y03235*
X03245Y03241*
X03242Y03246*
X03237Y0325*
X0323Y03251*
G37*
G36*
X03138Y03207D02*
X03083D01*
X03075Y03205*
X03069Y03201*
X03065Y03194*
X03063Y03187*
X03065Y03179*
X03069Y03172*
X03075Y03168*
X03083Y03167*
X03138*
X03146Y03168*
X03153Y03172*
X03154Y03174*
X03178*
X03182Y03171*
X03188Y0317*
X03195Y03171*
X032Y03175*
X03204Y0318*
X03205Y03187*
X03204Y03193*
X032Y03198*
X03195Y03202*
X03188Y03203*
X03182Y03202*
X03178Y03199*
X03154*
X03153Y03201*
X03146Y03205*
X03138Y03207*
G37*
G36*
X04477Y03151D02*
X04471Y0315D01*
X04466Y03146*
X04462Y03141*
X04461Y03135*
X04461Y03133*
X04453Y03124*
X04447Y03126*
X04446Y03128*
X04446Y03128*
X04448Y03135*
X04446Y03141*
X04443Y03146*
X04438Y0315*
X04431Y03151*
X04425Y0315*
X0442Y03146*
X04416Y03141*
X04415Y03135*
X04416Y03128*
X04418Y03126*
Y0312*
X04397Y03099*
X04374*
Y03056*
X04415*
Y03079*
X04429Y03094*
X04434Y03092*
Y03056*
X04475*
Y03099*
X04471*
X04469Y03104*
X04486Y0312*
X04487Y03121*
X04489Y03123*
X04492Y03128*
X04494Y03135*
X04492Y03141*
X04489Y03146*
X04484Y0315*
X04477Y03151*
G37*
G36*
X03138Y03157D02*
X03083D01*
X03075Y03155*
X03069Y03151*
X03065Y03144*
X03063Y03137*
X03065Y03129*
X03069Y03122*
X03075Y03118*
X03083Y03117*
X03138*
X03146Y03118*
X03153Y03122*
X03153Y03123*
X03172*
X03176Y0312*
X03183Y03119*
X03189Y0312*
X03194Y03124*
X03198Y03129*
X03199Y03135*
X03198Y03142*
X03194Y03147*
X03189Y0315*
X03183Y03152*
X03176Y0315*
X03172Y03148*
X03155*
X03153Y03151*
X03146Y03155*
X03138Y03157*
G37*
G36*
X02784D02*
X02729D01*
X02721Y03155*
X02715Y03151*
X0271Y03144*
X02709Y03137*
X0271Y03129*
X02715Y03122*
X02721Y03118*
X02729Y03117*
X02784*
X02792Y03118*
X02798Y03122*
X02803Y03129*
X02804Y03137*
X02803Y03144*
X02798Y03151*
X02792Y03155*
X02784Y03157*
G37*
G36*
X03939Y03137D02*
X03933Y03136D01*
X03928Y03132*
X03924Y03127*
X03923Y03121*
X03924Y03114*
X03928Y03109*
X03933Y03105*
X03939Y03104*
X03946Y03105*
X03951Y03109*
X03954Y03114*
X03956Y03121*
X03954Y03127*
X03951Y03132*
X03946Y03136*
X03939Y03137*
G37*
G36*
X03806Y03251D02*
X038Y0325D01*
X03795Y03246*
X03791Y03241*
X0379Y03235*
X03791Y03228*
X03793Y03226*
X03789Y03222*
X03787*
X03749*
Y03179*
X03772*
X03852Y03099*
X03856Y03096*
X03861Y03095*
X03871*
X03874Y03093*
X0388Y03092*
X03887Y03093*
X03892Y03097*
X03895Y03102*
X03897Y03109*
X03895Y03115*
X03892Y0312*
X03887Y03124*
X0388Y03125*
X03874Y03124*
X03871Y03122*
X03867*
X03858Y03131*
X0386Y03135*
X03861Y03135*
X03866Y03139*
X03869Y03144*
X03871Y03151*
X03869Y03157*
X03866Y03162*
X03861Y03166*
X03854Y03167*
X03848Y03166*
X03848Y03165*
X03844Y03169*
X03844Y03169*
X03846Y03176*
X03844Y03182*
X03841Y03187*
X03836Y03191*
X03829Y03192*
X03823Y03191*
X03818Y03187*
X03816Y03184*
X0381Y03183*
X0381Y03183*
X0381Y03188*
X03811Y03189*
X03814Y03194*
X03816Y03201*
X03814Y03207*
X03811Y03212*
X03809Y03214*
X0381Y03219*
X03813Y03219*
X03818Y03223*
X03821Y03228*
X03823Y03235*
X03821Y03241*
X03818Y03246*
X03813Y0325*
X03806Y03251*
G37*
G36*
X03138Y03107D02*
X03083D01*
X03075Y03105*
X03069Y03101*
X03065Y03094*
X03063Y03087*
X03065Y03079*
X03069Y03072*
X03075Y03068*
X03083Y03067*
X03138*
X03146Y03068*
X03153Y03072*
X03157Y03079*
X03158Y03087*
X03157Y03094*
X03153Y03101*
X03146Y03105*
X03138Y03107*
G37*
G36*
X02784D02*
X02729D01*
X02721Y03105*
X02715Y03101*
X0271Y03094*
X02709Y03087*
X0271Y03079*
X02715Y03072*
X02721Y03068*
X02729Y03067*
X02784*
X02792Y03068*
X02798Y03072*
X02803Y03079*
X02804Y03087*
X02803Y03094*
X02798Y03101*
X02792Y03105*
X02784Y03107*
G37*
G36*
X04068Y03151D02*
X04062Y0315D01*
X04057Y03146*
X04053Y03141*
X04053Y03138*
X04043Y03128*
X0404Y03124*
X04039Y0312*
X04013*
Y03064*
X04066*
Y03114*
X04071Y03119*
X04075Y03119*
X0408Y03123*
X04083Y03128*
X04085Y03135*
X04083Y03141*
X0408Y03146*
X04075Y0315*
X04068Y03151*
G37*
G36*
X04333D02*
X04327Y0315D01*
X04322Y03146*
X04318Y03141*
X04317Y03135*
X04318Y03128*
X04321Y03124*
Y03099*
X04314*
Y03056*
X04355*
Y03099*
X04348*
Y03127*
X04348Y03128*
X0435Y03135*
X04348Y03141*
X04345Y03146*
X0434Y0315*
X04333Y03151*
G37*
G36*
X04272D02*
X04266Y0315D01*
X04261Y03146*
X04257Y03141*
X04256Y03135*
X04257Y03128*
X04259Y03126*
Y03099*
X04254*
Y03056*
X04295*
Y03099*
X04286*
Y03126*
X04287Y03128*
X04289Y03135*
X04287Y03141*
X04284Y03146*
X04279Y0315*
X04272Y03151*
G37*
G36*
X0424Y03282D02*
X04178D01*
Y03209*
X04196*
Y03144*
X04193Y03141*
X04192Y03135*
X04193Y03128*
X04197Y03123*
X04199Y03121*
X042Y0312*
X04206Y03114*
Y03099*
X04199*
Y03056*
X0424*
Y03099*
X04233*
Y0312*
X04232Y03125*
X04229Y03129*
X04224Y03133*
X04225Y03135*
X04223Y03141*
X04222Y03143*
Y03209*
X0424*
Y03282*
G37*
G36*
X04152Y03151D02*
X04146Y0315D01*
X04141Y03146*
X04137Y03141*
X04136Y03135*
X04137Y03128*
X04141Y03123*
X04141Y03123*
X04141Y03122*
X04144Y03118*
X04151Y03111*
Y03099*
X04144*
Y03056*
X04185*
Y03099*
X04178*
Y03117*
X04177Y03122*
X04174Y03126*
X04168Y03132*
X04169Y03135*
X04167Y03141*
X04164Y03146*
X04159Y0315*
X04152Y03151*
G37*
G36*
X04114D02*
X04108Y0315D01*
X04103Y03146*
X04099Y03141*
X04098Y03135*
X04098Y03133*
X04097Y03131*
X04096Y03126*
Y03099*
X04089*
Y03056*
X0413*
Y03099*
X04123*
Y0312*
X04124Y03121*
X04126Y03123*
X04129Y03128*
X04131Y03135*
X04129Y03141*
X04126Y03146*
X04121Y0315*
X04114Y03151*
G37*
G36*
X0373Y03148D02*
X03657D01*
Y03086*
X03704*
Y03081*
X03702Y03078*
X03701Y03072*
X03702Y03065*
X03706Y0306*
X03711Y03056*
X03717Y03055*
X03724Y03056*
X03729Y0306*
X03732Y03065*
X03734Y03072*
X03732Y03078*
X03731Y03081*
Y03093*
X0373Y03095*
Y03099*
X0373Y03101*
Y03148*
G37*
G36*
X03138Y03057D02*
X03083D01*
X03075Y03055*
X03069Y03051*
X03065Y03044*
X03063Y03037*
X03065Y03029*
X03069Y03022*
X03075Y03018*
X03083Y03017*
X03138*
X03146Y03018*
X03153Y03022*
X03157Y03029*
X03158Y03037*
X03157Y03044*
X03153Y03051*
X03146Y03055*
X03138Y03057*
G37*
G36*
X02784D02*
X02729D01*
X02721Y03055*
X02715Y03051*
X0271Y03044*
X02709Y03037*
X0271Y03029*
X02715Y03022*
X02721Y03018*
X02729Y03017*
X02784*
X02792Y03018*
X02798Y03022*
X02803Y03029*
X02804Y03037*
X02803Y03044*
X02798Y03051*
X02792Y03055*
X02784Y03057*
G37*
G36*
X03138Y03007D02*
X03083D01*
X03075Y03005*
X03069Y03001*
X03065Y02994*
X03063Y02987*
X03065Y02979*
X03069Y02972*
X03075Y02968*
X03083Y02967*
X03138*
X03146Y02968*
X03153Y02972*
X03157Y02979*
X03158Y02987*
X03157Y02994*
X03153Y03001*
X03146Y03005*
X03138Y03007*
G37*
G36*
X02784D02*
X02729D01*
X02721Y03005*
X02715Y03001*
X0271Y02994*
X02709Y02987*
X0271Y02979*
X02715Y02972*
X02721Y02968*
X02729Y02967*
X02784*
X02792Y02968*
X02798Y02972*
X02803Y02979*
X02804Y02987*
X02803Y02994*
X02798Y03001*
X02792Y03005*
X02784Y03007*
G37*
G36*
X03138Y02957D02*
X03083D01*
X03075Y02955*
X03069Y02951*
X03065Y02944*
X03063Y02937*
X03065Y02929*
X03069Y02922*
X03075Y02918*
X03083Y02917*
X03138*
X03146Y02918*
X03153Y02922*
X03157Y02929*
X03158Y02937*
X03157Y02944*
X03153Y02951*
X03146Y02955*
X03138Y02957*
G37*
G36*
X02784D02*
X02729D01*
X02721Y02955*
X02715Y02951*
X0271Y02944*
X02709Y02937*
X0271Y02929*
X02715Y02922*
X02721Y02918*
X02729Y02917*
X02784*
X02792Y02918*
X02798Y02922*
X02803Y02929*
X02804Y02937*
X02803Y02944*
X02798Y02951*
X02792Y02955*
X02784Y02957*
G37*
%LNgrandmaster-3*%
%LPD*%
G54D13*
X02606Y00931D02*
X02608Y00934D01*
X02606Y00878D02*
Y00931D01*
X02409Y01038D02*
Y01088D01*
X02724Y01093D02*
X02724Y0109D01*
Y01038D02*
Y0109D01*
X02783Y01038D02*
Y01091D01*
X02784Y01094*
X02842Y01095D02*
X02842Y01095D01*
Y01038D02*
Y01095D01*
X02311Y00933D02*
X02311Y00934D01*
X02783Y02358D02*
Y02429D01*
X03463Y01713D02*
X03491D01*
X02475Y02456D02*
X02488Y02468D01*
X03556Y02047D02*
X03571Y02033D01*
X02586Y02317D02*
Y02358D01*
X02881Y02566D02*
X02882Y02565D01*
X03571Y02033D02*
X03594D01*
X01721Y01988D02*
X01776D01*
X02291Y02518D02*
X02291Y02518D01*
X02291Y02316D02*
Y02358D01*
X01718Y01497D02*
X01719Y01496D01*
X03571Y02033D02*
X03586Y02047D01*
X03596Y01514D02*
X03598Y01516D01*
X02488Y02412D02*
X02488Y02413D01*
X02291Y02556D02*
X02321Y02586D01*
X03409Y01465D02*
Y01468D01*
X01722Y01693D02*
X01776D01*
X02685Y02311D02*
Y02358D01*
X03457Y01516D02*
X03492D01*
X02901Y01095D02*
X02901Y01094D01*
X0239Y0256D02*
X02408Y02579D01*
X03594Y02033D02*
X03599Y02028D01*
X02586Y02518D02*
Y02568D01*
X02882Y02518D02*
Y02565D01*
X01645Y01497D02*
X01671D01*
X02488Y02468D02*
Y02518D01*
X03492Y02087D02*
X03542D01*
X02783Y02518D02*
Y02568D01*
X03414Y01805D02*
X03421Y01811D01*
X02488Y02358D02*
Y02412D01*
X02311Y0109D02*
X02312Y01091D01*
X02606Y0109D02*
X02606Y01091D01*
X03409Y01468D02*
X03448Y01506D01*
X02508Y01089D02*
X02508Y0109D01*
X01671Y01398D02*
X01671Y01399D01*
X02901Y00921D02*
X02933Y00953D01*
X03601Y02087D02*
X03651D01*
Y01418D02*
X03732D01*
X01717Y01398D02*
X01776D01*
X03718Y01713D02*
X03718Y01713D01*
X01722Y0189D02*
X01776D01*
X0167Y01693D02*
X0167Y01694D01*
X02311Y00878D02*
Y00933D01*
X03571Y02058D02*
X03581Y02067D01*
X0359Y01634D02*
Y01662D01*
X03491Y01713D02*
X03492Y01713D01*
X02408Y02579D02*
X02409D01*
X02685Y02518D02*
Y02567D01*
X03599Y02028D02*
X03651D01*
X03609Y01614D02*
X03651D01*
X01617Y01988D02*
X01674D01*
X02409Y00878D02*
Y00932D01*
X02882Y02307D02*
Y02358D01*
X03463Y01713D02*
X03463Y01713D01*
X0239Y02358D02*
Y02397D01*
X02253Y02279D02*
X02291Y02316D01*
X03581Y02067D02*
X03601Y02087D01*
X03594Y01514D02*
X03596D01*
X01675Y0189D02*
X01675Y01891D01*
X02665Y01038D02*
Y01091D01*
X03406Y01462D02*
X03409Y01465D01*
X01715Y01595D02*
X01776D01*
X01721Y01989D02*
X01721Y01988D01*
X03413Y01573D02*
Y01593D01*
X01721Y0189D02*
X01722Y0189D01*
X02508Y01038D02*
Y01089D01*
X0239Y02397D02*
X02404Y02412D01*
X01617Y01398D02*
X01671D01*
X02901Y00878D02*
Y00921D01*
X03581Y02067D02*
X03651D01*
X01617Y0189D02*
X01675D01*
X02665Y01091D02*
X02665Y01092D01*
X03651Y01713D02*
X03718D01*
X03406Y01461D02*
Y01462D01*
X02508Y00878D02*
Y00931D01*
X02311Y01038D02*
Y0109D01*
X02606Y01038D02*
Y0109D01*
X03448Y01506D02*
Y01507D01*
X01718Y01792D02*
X01718Y01792D01*
X03548Y01413D02*
X03549D01*
X01645Y01496D02*
X01645Y01497D01*
X01617Y01792D02*
X01671D01*
X03492Y02067D02*
X03562D01*
X01617Y01693D02*
X0167D01*
X02581Y02312D02*
X02586Y02317D01*
X03562Y02067D02*
X03571Y02058D01*
X0359Y01634D02*
X03609Y01614D01*
X01674Y01988D02*
X01674Y01989D01*
X02871Y02297D02*
X02882Y02307D01*
X02685Y02567D02*
X02685Y02568D01*
X0341Y01713D02*
X03463D01*
X03421Y01811D02*
X03492D01*
X02901Y01038D02*
Y01094D01*
X02291Y02518D02*
Y02556D01*
X0239Y02518D02*
Y0256D01*
X03492Y02028D02*
X0355D01*
X01719Y01496D02*
X01776D01*
X03586Y02047D02*
X03651D01*
X03598Y01516D02*
X03651D01*
X01617Y01595D02*
X0167D01*
X03492Y02047D02*
X03556D01*
X01714Y01595D02*
X01715Y01595D01*
X02586Y02569D02*
X02586Y02568D01*
X03413Y01593D02*
X03435Y01614D01*
X01721Y01694D02*
X01722Y01693D01*
X02685Y02311D02*
X02685Y02311D01*
X03448Y01507D02*
X03457Y01516D01*
X03435Y01614D02*
X03492D01*
X0167Y01595D02*
X0167Y01595D01*
X0355Y02028D02*
X03554Y02033D01*
X01718Y01792D02*
X01776D01*
X03543Y01418D02*
X03548Y01413D01*
X01617Y01496D02*
X01645D01*
X01617Y01792D02*
X01617Y01792D01*
X03542Y02087D02*
X03562Y02067D01*
X01617Y01496D02*
X01617Y01496D01*
X03554Y02033D02*
X03571D01*
X01716Y01399D02*
X01717Y01398D01*
X03492Y01418D02*
X03543D01*
X0333Y03301D02*
Y03392D01*
X03333Y03395*
X01726Y04329D02*
X01727Y04328D01*
Y04273D02*
Y04328D01*
X01788Y04289D02*
Y04329D01*
X01933Y04257D02*
D01*
X01873Y04281D02*
X0189Y04299D01*
X01873Y0427D02*
Y04281D01*
X01933Y04129D02*
Y04257D01*
X04476Y03129D02*
Y03133D01*
X04477Y03135*
X04454Y03108D02*
X04476Y03129D01*
X04064Y02722D02*
Y0278D01*
X06628Y01372D02*
X06629Y01372D01*
Y01421*
X07011Y01939D02*
X07015Y01943D01*
X06974Y01939D02*
X07011D01*
X03911Y01639D02*
X03911Y01639D01*
X03957Y01659D02*
X03968Y01671D01*
X04033Y01547D02*
X04034Y01546D01*
X03925Y01599D02*
X03951D01*
X03925Y01599D02*
X03925Y01599D01*
X03911Y01599D02*
X03925D01*
X03969Y01552D02*
Y01581D01*
X03911Y01619D02*
X03911Y01619D01*
X03964D02*
X03994Y01589D01*
X0413Y01686D02*
X04131D01*
X04068Y01679D02*
X04123D01*
X04033Y01547D02*
Y01575D01*
X03996Y01711D02*
X04025Y01739D01*
X03994Y01551D02*
Y01589D01*
X04025Y01739D02*
X04068D01*
X03911Y01619D02*
X03964D01*
X03911Y01639D02*
X03969D01*
X04033Y01575*
X04123Y01679D02*
X0413Y01686D01*
X03911Y01659D02*
X03957D01*
X03951Y01599D02*
X03969Y01581D01*
X03959Y02725D02*
X0396Y02724D01*
X03959Y02725D02*
Y0278D01*
X03625Y00726D02*
X03659D01*
X03603Y00704D02*
X03625Y00726D01*
X03603Y00682D02*
Y00704D01*
X06439Y03026D02*
Y03071D01*
Y03026D02*
X06456Y03009D01*
X06619Y03039D02*
X06626Y03032D01*
X06584Y03039D02*
X06619D01*
X01908Y04129D02*
X01933D01*
X01878Y04099D02*
X01908Y04129D01*
X01846Y04099D02*
X01878D01*
X01914Y04276D02*
X01933Y04257D01*
X01879Y04276D02*
X01914D01*
X01873Y04244D02*
Y0427D01*
X01853Y04225D02*
X01873Y04244D01*
X01687Y04225D02*
X01853D01*
X01664Y04248D02*
X01687Y04225D01*
X01664Y04248D02*
Y04273D01*
X03477Y02797D02*
X03484Y02804D01*
Y02892*
X01788Y04289D02*
X01802Y04276D01*
X03772Y03758D02*
X03825D01*
X03829Y03762*
X0383*
X03344Y04221D02*
X03394D01*
X03395Y04222*
X04272Y03079D02*
X04274Y03077D01*
X04272Y03079D02*
Y03135D01*
X02139Y03697D02*
Y03738D01*
X04209Y03135D02*
Y03246D01*
X04208Y03135D02*
X04209Y03135D01*
X04209Y03129D02*
X04219Y0312D01*
X04209Y03129D02*
Y03133D01*
X04208Y03135D02*
X04209Y03133D01*
X04219Y03077D02*
Y0312D01*
X04164Y03077D02*
Y03117D01*
X04153Y03127D02*
X04164Y03117D01*
X04153Y03127D02*
Y03133D01*
X04152Y03135D02*
X04153Y03133D01*
X01157Y01956D02*
Y01956D01*
X012Y02*
X01248*
X04039Y03092D02*
X04052Y03105D01*
Y03119*
X04068Y03135*
X01631Y04099D02*
X01671D01*
X01691Y04079*
X03642Y00636D02*
X03682D01*
X03987Y03783D02*
X04039D01*
X04039Y03784*
X06477Y03231D02*
X06511D01*
X06476Y03231D02*
X06477Y03231D01*
X04334Y03077D02*
Y03134D01*
X04333Y03135D02*
X04334Y03134D01*
X04454Y03077D02*
Y03108D01*
X01873Y0427D02*
Y04276D01*
X01601Y04273D02*
X01664D01*
X01557Y04229D02*
X01601Y04273D01*
X01157Y02481D02*
X0126D01*
X01261Y02482*
X04109Y03077D02*
Y03126D01*
X04113Y03129*
Y03133*
X04114Y03135*
X06604Y03327D02*
X06618Y03341D01*
X06648*
X02888Y04221D02*
X02944D01*
X02888Y04221D02*
X02888Y04221D01*
X03434Y02888D02*
X03438Y02892D01*
X0337Y02888D02*
X03434D01*
X02233Y03734D02*
Y03735D01*
X02239Y03741*
X02209Y03716D02*
X02215D01*
X02233Y03734*
X02239Y03741D02*
X02258D01*
X01764Y04124D02*
X01846D01*
X01749Y0411D02*
X01764Y04124D01*
X02281Y0417D02*
Y04207D01*
X0229Y04217*
X03769Y032D02*
Y03201D01*
Y032D02*
X03777Y03192D01*
X03778*
X03861Y03109*
X0388*
X03688Y03329D02*
X03701Y03342D01*
X03744*
X03693Y03117D02*
X03699D01*
X03717Y03099*
Y03094D02*
Y03099D01*
Y03094D02*
X03717Y03093D01*
Y03072D02*
Y03093D01*
X05733Y03361D02*
Y03556D01*
X05676Y03362D02*
Y03545D01*
X05676Y03546*
X03659Y00723D02*
Y00726D01*
X06548Y01531D02*
X06629D01*
X06603Y01611D02*
X06642D01*
X06602Y01612D02*
X06603Y01611D01*
Y01671D02*
X06642D01*
X06602Y01672D02*
X06603Y01671D01*
Y01721D02*
X06642D01*
X06602Y01722D02*
X06603Y01721D01*
X06602Y01776D02*
X06642D01*
X06601Y01777D02*
X06602Y01776D01*
X06727Y01816D02*
Y01818D01*
X06718Y01828D02*
X06727Y01818D01*
X06685Y01828D02*
X06718D01*
X06637Y01881D02*
X06699D01*
X07009Y01938D02*
X0701Y01939D01*
X06906Y02096D02*
X06948D01*
X06949Y02095*
X0665Y02176D02*
X06659Y02166D01*
X06607Y02176D02*
X0665D01*
X06334Y0211D02*
X06395D01*
X06395Y02111*
X06048Y02171D02*
X06093D01*
X06004Y02393D02*
Y02434D01*
X06274Y02391D02*
X06352D01*
X06367Y02451D02*
X06369Y02453D01*
X06398*
X06361Y02501D02*
X06397D01*
X06361Y02556D02*
X06396D01*
X06361Y02611D02*
X06396D01*
X06397Y0261*
X06361Y02656D02*
X06397D01*
X06398Y02657*
X04954Y04203D02*
X04957Y04206D01*
X0491Y04203D02*
X04954D01*
X04387Y04206D02*
X04432D01*
X03778Y04023D02*
X03779Y04023D01*
X03777Y04023D02*
X03778D01*
X03779Y04023D02*
X03808D01*
X04104Y03841D02*
X04104Y03841D01*
X04104Y03841D02*
Y03873D01*
X04085Y03892D02*
X04104Y03873D01*
X04194Y03837D02*
Y03884D01*
X04394Y03077D02*
Y03078D01*
X04402Y03086*
X04403*
X04431Y03114*
Y03135*
X0286Y0375D02*
Y03784D01*
X0286Y03785*
X02745Y03742D02*
Y0375D01*
X0274Y03737D02*
X02745Y03742D01*
X02732Y03737D02*
X0274D01*
X02724Y03729D02*
X02732Y03737D01*
X02724Y03729D02*
Y03729D01*
X03495Y03697D02*
X03531Y03661D01*
Y0366D02*
Y03661D01*
X03495Y03697D02*
Y0375D01*
X0327D02*
Y03784D01*
X03269Y03785D02*
X0327Y03784D01*
X01157Y01431D02*
X01198Y01472D01*
X01242*
X01157Y00906D02*
X01193Y00942D01*
X01256*
X00654Y0079D02*
Y00847D01*
Y00964D02*
Y01027D01*
X00655Y01028*
X00654Y01314D02*
Y01372D01*
Y01489D02*
Y0155D01*
X00653Y01551D02*
X00654Y0155D01*
Y01839D02*
Y01897D01*
Y02014D02*
Y02073D01*
Y02365D02*
Y02422D01*
Y02539D02*
Y02593D01*
X00653Y02593D02*
X00654Y02593D01*
G54D17*
X01776Y02028D02*
X01776Y02028D01*
X01776Y02008D02*
X01776Y02008D01*
X03491Y01397D02*
X03492Y01398D01*
X03407Y01411D02*
X03431D01*
X03444Y01398*
X03492*
G54D19*
X02684Y02716D02*
D01*
X02685Y02716*
X02685Y02716*
X02686Y02716*
X02686Y02716*
X02687Y02717*
X02687Y02717*
X02688Y02717*
X02688Y02717*
X02689Y02718*
X02689Y02718*
X0269Y02718*
X0269Y02718*
X02449D02*
D01*
X02449Y02718*
X0245Y02718*
X0245Y02717*
X02451Y02717*
X02451Y02717*
X02452Y02717*
X02452Y02716*
X02453Y02716*
X02453Y02716*
X02454Y02716*
X02454Y02716*
X02455Y02716*
X02928Y00161D02*
D01*
X02929Y00159*
X02929Y00157*
X02929Y00154*
X0293Y00152*
X02931Y0015*
X02931Y00148*
X02932Y00145*
X02934Y00143*
X02935Y00141*
X02936Y00139*
X02938Y00138*
X02938Y00137*
X02378Y02789D02*
X02449Y02718D01*
X0269D02*
X02692Y02721D01*
X02455Y02716D02*
X02684D01*
X02494Y02614D02*
Y02661D01*
X03055Y00159D02*
Y00573D01*
Y00159D02*
X03057Y00157D01*
X02505Y00137D02*
X02507Y00139D01*
Y00271*
X02539Y00303D02*
Y00429D01*
X02507Y00271D02*
X02539Y00303D01*
X02503Y00464D02*
X02539Y00429D01*
X02503Y00464D02*
Y00573D01*
X0205Y00607D02*
X02503D01*
X01797Y00355D02*
X0205Y00607D01*
X02503D02*
X03055D01*
X03588Y02686D02*
Y0287D01*
X03534Y02888D02*
X03569D01*
X03588Y0287*
X03531Y02892D02*
X03534Y02888D01*
X03278Y01673D02*
X03492D01*
X03244Y01681D02*
X03271D01*
X03278Y01673*
X03252Y01661D02*
X03265D01*
X03272Y01654D02*
X03492D01*
X03265Y01661D02*
X03272Y01654D01*
X04133Y01751D02*
X04134Y01751D01*
X04121Y01751D02*
X04133D01*
X04068Y01759D02*
X04113D01*
X04121Y01751*
X04171Y01751D02*
X04727Y02307D01*
X04134Y01751D02*
X04171D01*
X04243Y01623D02*
X04927Y02307D01*
X0415Y01623D02*
X04243D01*
X05061Y01074D02*
Y02407D01*
Y01074D02*
X05127Y01007D01*
X05211Y01133D02*
Y0234D01*
X05327Y01007D02*
Y01017D01*
X05211Y01133D02*
X05327Y01017D01*
X04873Y02595D02*
X05061Y02407D01*
X04893Y02658D02*
X05211Y0234D01*
X0492Y02714D02*
X05327Y02307D01*
X04729Y02714D02*
X0492D01*
X02449Y02285D02*
Y02358D01*
Y02597D02*
X02463Y02612D01*
X02311Y02358D02*
X02331D01*
X01754Y02088D02*
X01755Y02087D01*
X03329Y01826D02*
X03405D01*
X02665Y02291D02*
Y02358D01*
X03492Y02008D02*
X03537D01*
X02894Y02465D02*
X02901Y02472D01*
X0292Y02517D02*
X02921Y02518D01*
X02841Y02299D02*
X02862Y02319D01*
X02499Y02236D02*
X02527Y02264D01*
X02429Y02303D02*
Y02322D01*
X02468Y02518D02*
Y02588D01*
X03491Y0185D02*
X03492Y01851D01*
X03378Y01971D02*
X03459Y0189D01*
X01567Y01285D02*
Y0131D01*
X03651Y01477D02*
X03652Y01478D01*
X03773Y01665D02*
Y01666D01*
X03409Y01363D02*
X03413Y01359D01*
X01776Y01516D02*
X01897D01*
X01719Y01536D02*
X01776D01*
X0298Y02518D02*
Y02599D01*
X03234Y01752D02*
X03492D01*
X0376Y01792D02*
X03804Y01836D01*
X02645Y02299D02*
X02646Y02299D01*
X02449Y02285D02*
X0245Y02284D01*
X02821Y02601D02*
X02823Y02599D01*
X03555Y0189D02*
X03651D01*
X02429Y02322D02*
X02429Y02322D01*
X02803Y02307D02*
Y02358D01*
X02645Y02274D02*
Y02299D01*
X02624Y02461D02*
X02626Y02459D01*
X0298Y02358D02*
Y02396D01*
X02862Y02319D02*
Y02358D01*
X02624Y02461D02*
X02625Y02461D01*
X02527Y02264D02*
Y02358D01*
X03412Y0185D02*
X03491D01*
X02646Y02299D02*
Y02358D01*
X01797Y01319D02*
X01798Y01318D01*
X02547Y02313D02*
Y02358D01*
X01617Y02087D02*
Y02118D01*
X03775Y01511D02*
X03864D01*
X03554Y01841D02*
X03584Y01811D01*
X03651Y01634D02*
X03696D01*
X03804Y01836D02*
Y0184D01*
X02429Y02322D02*
Y02358D01*
X02409Y02283D02*
X02429Y02303D01*
X02272Y02463D02*
Y02518D01*
X03699Y01654D02*
X03712Y01641D01*
X02449Y02518D02*
Y02597D01*
X01815Y01614D02*
X01893Y01693D01*
X03788Y01566D02*
X03894D01*
X03381Y01387D02*
X03422D01*
X02724Y02297D02*
X02726Y02295D01*
X01776Y01811D02*
X01879D01*
X01719Y01536D02*
X01719Y01536D01*
X02958Y02621D02*
X0298Y02599D01*
X03651Y02008D02*
X03707D01*
X03651Y0189D02*
X03651Y0189D01*
X02331Y02215D02*
Y02358D01*
X01776Y02067D02*
X01881D01*
X03405Y01826D02*
X03411Y01831D01*
X03459Y0189D02*
X03492D01*
X03422Y01387D02*
X03431Y01378D01*
X02961Y02311D02*
X02985Y02287D01*
X0235Y02676D02*
X02394Y0272D01*
X0235Y02518D02*
Y02676D01*
X03652Y01478D02*
X03831D01*
X03749Y01641D02*
X03773Y01665D01*
X0292Y02428D02*
X0292Y02428D01*
X01776Y01674D02*
X01822D01*
X01755Y02087D02*
X01776D01*
X02468Y02299D02*
Y02358D01*
X01617Y02118D02*
X01619Y02121D01*
X03528Y0191D02*
X03554Y01936D01*
X02702Y02293D02*
Y02295D01*
X03651Y0191D02*
X03708D01*
X03705Y01625D02*
X0377D01*
X03776Y01555D02*
X03795Y01536D01*
X03491Y0187D02*
X03492Y0187D01*
X02841Y02263D02*
Y02299D01*
X02702Y02295D02*
X02705Y02298D01*
X02409Y02314D02*
Y02358D01*
X01776Y01319D02*
X01797D01*
X03584Y01811D02*
X03651D01*
X03708Y0191D02*
X03719Y01921D01*
X03696Y01634D02*
X03705Y01625D01*
X03651Y01555D02*
X03776D01*
X03431Y01378D02*
X03492D01*
X02901Y02304D02*
X0292Y02286D01*
X02429Y02358D02*
X02429Y02358D01*
X02252Y02518D02*
Y02613D01*
X03712Y01641D02*
X03749D01*
X02547Y02313D02*
X02579Y02281D01*
X01776Y01614D02*
X01815D01*
X03651Y01575D02*
X03779D01*
X03197Y01714D02*
Y01715D01*
X03439Y0187D02*
X03491D01*
X03298Y01971D02*
X03378D01*
X0292Y02286D02*
X02942D01*
X02599Y02431D02*
Y02436D01*
X02468Y02588D02*
X02494Y02614D01*
X02894Y02431D02*
Y02465D01*
X02803Y02358D02*
X02803Y02358D01*
X02493Y02694D02*
X02494Y02696D01*
X01798Y01304D02*
Y01318D01*
X02948Y02428D02*
X0298Y02396D01*
X03492Y01438D02*
X03547D01*
X03715Y01772D02*
X03719Y01767D01*
X02901Y02304D02*
Y02358D01*
X02484Y02694D02*
X02493D01*
X01879Y01811D02*
X01882Y01809D01*
X01881Y02067D02*
X01884Y02071D01*
X03707Y02008D02*
X03719Y01996D01*
X02726Y02293D02*
Y02295D01*
X0233Y02215D02*
X02331Y02215D01*
X03392Y01871D02*
X03412Y0185D01*
X02823Y02518D02*
Y02599D01*
X01776Y01536D02*
X01776Y01536D01*
X01568Y02067D02*
X01617D01*
X03554Y01891D02*
X03555Y0189D01*
X03379Y01386D02*
X03381Y01387D01*
X02463Y02612D02*
Y02674D01*
X0292Y02428D02*
Y02517D01*
X01577Y01319D02*
X01617D01*
X03831Y01478D02*
X03834Y01481D01*
X03537Y02008D02*
X03554Y01991D01*
X03411Y01831D02*
X03492D01*
X02705Y0232D02*
Y02358D01*
X02901Y02472D02*
Y02518D01*
X02948Y02428D02*
Y02456D01*
X03761Y01496D02*
X03775Y01511D01*
X03492Y0191D02*
X03528D01*
X03804Y01659D02*
Y0169D01*
X02705Y0232D02*
X02705Y02319D01*
X02724Y02297D02*
Y02358D01*
X02475Y02291D02*
Y02292D01*
X0377Y01625D02*
X03804Y01659D01*
X03795Y01536D02*
X03924D01*
X03197Y01715D02*
X03234Y01752D01*
X03651Y01792D02*
X0376D01*
X03383Y01339D02*
X03492D01*
X02705Y02298D02*
Y02319D01*
X02468Y02299D02*
X02475Y02292D01*
X01754Y02088D02*
Y02126D01*
X03651Y01496D02*
X03761D01*
X03803Y01691D02*
X03804Y0169D01*
X03924Y01536D02*
D01*
X03404Y01363D02*
X03409D01*
X03379Y01336D02*
X03383Y01339D01*
X02961Y02311D02*
Y02358D01*
X02409Y02314D02*
X02409Y02314D01*
X02665Y02291D02*
X02665Y02291D01*
X02599Y02431D02*
X02606Y02424D01*
X02567Y02358D02*
Y02403D01*
X0245Y02282D02*
Y02284D01*
X03492Y01437D02*
X03492Y01438D01*
X03719Y01766D02*
Y01767D01*
X03413Y01359D02*
X03492D01*
X02606Y02358D02*
Y02424D01*
X02626Y02358D02*
Y02459D01*
X02567Y02403D02*
X02575Y02412D01*
X02463Y02674D02*
X02484Y02694D01*
X01567Y0131D02*
X01577Y01319D01*
X03779Y01575D02*
X03788Y01566D01*
X03651Y01654D02*
X03699D01*
X03651Y01772D02*
X03715D01*
X03547Y01438D02*
X03549Y01441D01*
X03224Y01661D02*
X03244Y01681D01*
X05577Y02214D02*
X05612D01*
X05634Y02236*
X04204Y03603D02*
X04275D01*
X03537Y02996D02*
X03547Y02985D01*
X03393Y03335D02*
X03431Y03297D01*
X03393Y03335D02*
Y03393D01*
Y03333D02*
Y03335D01*
X03392Y03395D02*
X03393Y03393D01*
X03328Y0327D02*
X0339Y03332D01*
X03431Y03297D02*
X03491D01*
X03205Y0327D02*
X03328D01*
X03425Y03666D02*
X03464D01*
X03349D02*
X03425D01*
X03424Y03636D02*
X03425Y03636D01*
Y03666*
X03464Y03648D02*
X03469Y03653D01*
X03608Y03727D02*
X03667Y03786D01*
X03589Y03727D02*
X03608D01*
X04141Y03594D02*
X0415Y03603D01*
X0412Y03594D02*
X04141D01*
X0096Y00714D02*
Y00718D01*
Y00714D02*
X00988Y00687D01*
X0099*
X00901Y00718D02*
Y00875D01*
X00932Y00906*
X04884Y02789D02*
X04887Y02786D01*
X04909Y02808D02*
D01*
X04794D02*
X04909D01*
X04794D02*
X04795Y02809D01*
X04909Y04118D02*
X0491Y04119D01*
X04909Y03961D02*
Y04118D01*
X04539Y02904D02*
X04729Y02714D01*
X04539Y02904D02*
Y03111D01*
X03112Y03135D02*
X03183D01*
X03111Y03137D02*
X03112Y03135D01*
X0491Y04119D02*
Y04203D01*
X03209Y02834D02*
Y02896D01*
X03271Y02958*
X03191Y02824D02*
Y02924D01*
X0325Y02983*
Y03042*
X03269Y02795D02*
Y02814D01*
X03297*
X0337Y02888*
X03487Y03101D02*
X03488Y03101D01*
X0331Y03101D02*
X03487D01*
X03491Y03101D02*
X03491Y03101D01*
X03484Y03094D02*
X03491Y03101D01*
X03488Y03101D02*
X03491D01*
X03111Y03187D02*
X03111Y03187D01*
X03188*
X03188Y03187*
X03111Y03237D02*
X03172D01*
X03205Y0327*
X03247Y03456D02*
X03297D01*
X03306Y03448D02*
X03358D01*
X03297Y03456D02*
X03306Y03448D01*
X03358D02*
X03377Y03467D01*
X03134Y03344D02*
X03247Y03456D01*
X03111Y03287D02*
X03127D01*
X03134Y03294*
Y03344*
X03068Y03395D02*
X03068Y03395D01*
X03048Y03395D02*
X03068D01*
X0284Y03187D02*
X03048Y03395D01*
X02756Y03187D02*
X0284D01*
X02146Y02679D02*
Y02753D01*
X03333Y0319D02*
Y03206D01*
X03285Y03143D02*
X03333Y0319D01*
X03277Y03143D02*
X03285D01*
X03275Y03141D02*
X03277Y03143D01*
X02378Y0289D02*
X02387Y02899D01*
X02378Y02789D02*
Y0289D01*
X02387Y02958D02*
X02389Y0296D01*
Y03481*
X02333D02*
X02389D01*
X02329Y03484D02*
X02333Y03481D01*
X02452Y03563D02*
X02504D01*
X02264Y03545D02*
X02311D01*
X02329Y03563*
X02504Y03484D02*
X02578D01*
X02434Y03546D02*
X02452Y03563D01*
X02254Y03536D02*
X02264Y03545D01*
X02504Y03406D02*
X02634D01*
X02578Y03484D02*
X02579Y03486D01*
X00995Y02257D02*
X00996Y02256D01*
X00967Y0228D02*
X0099Y02257D01*
X00995*
X02212Y04074D02*
X02242D01*
X02253Y04086*
X02146Y04076D02*
X02147Y04074D01*
X02146Y04076D02*
Y04103D01*
X02147Y04074D02*
X02151D01*
X01346Y03978D02*
X01348Y0398D01*
X01408*
X01345Y04142D02*
X01346Y04141D01*
X01345Y04142D02*
Y04175D01*
X00963Y0122D02*
Y01224D01*
Y0122D02*
X00996Y01187D01*
Y01187D02*
Y01187D01*
X00959Y01743D02*
Y01747D01*
Y01743D02*
X00983Y01719D01*
X00986*
X00988Y01717*
X00967Y0228D02*
Y02284D01*
X00904Y01224D02*
Y01402D01*
X00932Y01431*
X009Y01747D02*
Y01924D01*
X00932Y01956*
X00908Y02284D02*
Y02456D01*
X00932Y02481*
X02151Y04014D02*
X0221D01*
X02043Y04057D02*
X02086Y04014D01*
X02151*
X01715Y03963D02*
X02245D01*
X02332Y04051D02*
Y0417D01*
X02245Y03963D02*
X02332Y04051D01*
X02358Y04022D02*
Y0417D01*
X02353Y04017D02*
X02358Y04022D01*
X01346Y04037D02*
Y04082D01*
Y04037D02*
X01356Y04047D01*
X0145*
X01457Y04053*
Y04153D02*
X01487Y04124D01*
X01569Y04171D02*
Y04173D01*
X01594Y04197*
X01659Y04019D02*
X01715Y03963D01*
X0325Y03042D02*
X0331Y03101D01*
X03208Y02815D02*
X03209Y02814D01*
X032Y02815D02*
X03208D01*
X03191Y02824D02*
X032Y02815D01*
X03229Y02845D02*
Y0288D01*
X03344Y02996*
X04539Y03111D02*
Y03156D01*
X04243Y02658D02*
X04893D01*
X0418Y02595D02*
X04243Y02658D01*
X04298Y02595D02*
X04873D01*
X04187Y02469D02*
X04912D01*
X04062Y02595D02*
X04187Y02469D01*
X04992Y01071D02*
Y02389D01*
X04912Y02469D02*
X04992Y02389D01*
X04927Y02307D02*
D01*
X04126Y01631D02*
X04142D01*
X0415Y01623*
X04927Y01007D02*
X04992Y01071D01*
X04068Y01659D02*
X04126D01*
X04179Y01601D02*
D01*
X04065Y01599D02*
X04068D01*
X04064Y01511D02*
Y01598D01*
Y0178D02*
X04065Y01779D01*
X04068Y01619D02*
X04117D01*
X04064Y01598D02*
X04065Y01599D01*
X04117Y01619D02*
X04135Y01601D01*
X0392Y01791D02*
X03944Y01816D01*
X04135Y01601D02*
X04179D01*
X04118Y01639D02*
X04126Y01631D01*
X04126Y01659D02*
X04134Y01651D01*
X03911Y01779D02*
X03919D01*
X04134Y01651D02*
X04134D01*
X04068Y01639D02*
X04118D01*
X0392Y0178D02*
Y01791D01*
X03919Y01779D02*
X0392Y0178D01*
X04065Y01779D02*
X04068D01*
X04064Y0178D02*
Y01796D01*
X05812Y03302D02*
Y03361D01*
X01629Y04197D02*
X01631Y04199D01*
X01594Y04197D02*
X01629D01*
X01569Y04171D02*
D01*
X02527Y02518D02*
Y02582D01*
X02612Y02666D02*
X03568D01*
X02527Y02582D02*
X02612Y02666D01*
X03568D02*
X03588Y02686D01*
X01487Y04124D02*
X01631D01*
X03057Y0013D02*
X03059Y00132D01*
X01893Y04018D02*
X01903D01*
X01886Y04024D02*
X01893Y04018D01*
X01846Y04024D02*
X01886D01*
X02758Y03661D02*
X02797Y03701D01*
X02719Y03661D02*
X02758D01*
X02797Y03701D02*
X03D01*
X0373Y00731D02*
X03737Y00724D01*
X03979Y00808D02*
Y0089D01*
X03895Y00724D02*
X03979Y00808D01*
X03737Y00724D02*
X03895D01*
X03716Y00712D02*
X0373Y00726D01*
X03716Y00636D02*
Y00712D01*
X06679Y02339D02*
Y0242D01*
X06643Y02302D02*
X06679Y02339D01*
X06469Y02302D02*
X06643D01*
X06435D02*
X06469D01*
X06397Y02341D02*
X06435Y02302D01*
X06352Y02341D02*
X06397D01*
X06788Y01881D02*
X06832D01*
X06782Y01874D02*
X06788Y01881D01*
X06782Y01874D02*
Y01816D01*
X06897D02*
Y01864D01*
X0688Y01881D02*
X06897Y01864D01*
X06832Y01881D02*
X0688D01*
X06359Y0331D02*
X06388D01*
X06336Y03287D02*
X06359Y0331D01*
X06336Y03267D02*
Y03287D01*
X0649Y03172D02*
X06511D01*
X06489Y03173D02*
X0649Y03172D01*
X0642Y0313D02*
Y0315D01*
X0641Y03121D02*
X0642Y0313D01*
X06304Y03121D02*
X0641D01*
X01017Y03836D02*
X02029D01*
X0084Y04013D02*
X01017Y03836D01*
X00835Y03816D02*
X02004D01*
X00638Y04012D02*
X00835Y03816D01*
X00638Y04012D02*
Y04038D01*
X01363Y03896D02*
X02084D01*
X01243Y04015D02*
X01363Y03896D01*
X01243Y04015D02*
Y04038D01*
X01185Y03871D02*
X02059D01*
X01042Y04014D02*
X01185Y03871D01*
X01042Y04014D02*
Y04038D01*
X0084Y04013D02*
Y04038D01*
X01774Y04049D02*
X01846D01*
X01676Y04147D02*
X01774Y04049D01*
X01633Y04147D02*
X01676D01*
X02146Y02578D02*
Y02624D01*
X02108Y0254D02*
X02146Y02578D01*
X02108Y01728D02*
Y0254D01*
X02229Y02586D02*
X02232Y02583D01*
Y02518D02*
Y02583D01*
X06604Y03192D02*
X06704D01*
X06726Y0317*
Y03168D02*
Y0317D01*
X06604Y03191D02*
X06604Y03192D01*
X06511Y03191D02*
X06604D01*
X06604Y03264D02*
X06704D01*
X06726Y03286*
Y03294*
X06604Y03263D02*
Y03264D01*
X06552Y03211D02*
X06604Y03263D01*
X06511Y03211D02*
X06552D01*
X00644Y04099D02*
Y04197D01*
X00638Y04093D02*
X00644Y04099D01*
X00846D02*
Y04192D01*
X0084Y04093D02*
X00846Y04099D01*
X03053Y00571D02*
X03055Y00573D01*
X06234Y02183D02*
Y02241D01*
X06184Y02291D02*
X06234Y02241D01*
X06157Y02291D02*
X06184D01*
X06804Y01881D02*
X06832D01*
X06122Y02433D02*
X06128D01*
X06138Y02423*
Y02418D02*
Y02423D01*
Y02418D02*
X06147Y02409D01*
Y02398D02*
Y02409D01*
Y02398D02*
X06154Y02391D01*
X06157*
X06184*
X06244Y02451*
X06312*
X02944Y03745D02*
Y03951D01*
X03144Y03745D02*
Y03951D01*
X03349Y03745D02*
Y03946D01*
X03344Y03951D02*
X03349Y03946D01*
X04112Y03701D02*
Y03706D01*
X04085Y03733D02*
X04112Y03706D01*
X03987Y03733D02*
X04085D01*
X04566Y04206D02*
X04652D01*
Y04121D02*
Y04206D01*
D01*
X05091D02*
X05212D01*
Y04126D02*
Y04206D01*
Y04126D02*
D01*
X01846Y04074D02*
X01933D01*
X01933Y04074*
X04049Y03665D02*
Y03694D01*
X04035Y03708D02*
X04049Y03694D01*
X03987Y03708D02*
X04035D01*
X03827Y03808D02*
X03829Y03806D01*
X03772Y03808D02*
X03827D01*
X01631Y04149D02*
X01633Y04147D01*
X06379Y03309D02*
X06388D01*
X06388Y0331D02*
X06388Y03309D01*
X06334Y03266D02*
Y03269D01*
Y03266D02*
X06336Y03267D01*
X0373Y00726D02*
Y00731D01*
X03368Y0305D02*
X03371D01*
X03372Y03051*
X03438*
X06347Y0325D02*
X06388D01*
X06343Y03246D02*
X06347Y0325D01*
X06302Y03246D02*
X06343D01*
X06282Y03226D02*
X06302Y03246D01*
X01897Y01516D02*
X02108Y01728D01*
X02141Y02624D02*
X02146D01*
X01631Y04024D02*
X01653D01*
X01658Y04019*
X01659*
X03484Y03051D02*
Y03094D01*
X03566Y03486D02*
X03622D01*
X03518Y03437D02*
X03566Y03486D01*
X0351Y03395D02*
X03518Y03403D01*
Y03437*
X03345Y02995D02*
X03444D01*
X03344Y02996D02*
X03345Y02995D01*
X06311Y03201D02*
X06331D01*
X06362Y03231D02*
X06388D01*
X06331Y03201D02*
X06362Y03231D01*
X06309Y03199D02*
X06311Y03201D01*
X03377Y03467D02*
X03403D01*
X03423Y03431D02*
Y03435D01*
X03414Y03444D02*
Y03455D01*
X03423Y03431D02*
X03428Y03426D01*
X03435D02*
X03451Y0341D01*
X03403Y03467D02*
X03414Y03455D01*
X03451Y03395D02*
Y0341D01*
X03428Y03426D02*
X03435D01*
X03414Y03444D02*
X03423Y03435D01*
X06447Y03396D02*
X06459Y03383D01*
Y03332D02*
Y03383D01*
X02829Y03655D02*
X02834Y03661D01*
X02829Y03645D02*
Y03655D01*
X02799Y03616D02*
X02829Y03645D01*
X03589Y01711D02*
X03591D01*
X00932Y00906D02*
X01004D01*
X00932Y01431D02*
X01007D01*
X01008Y0143*
X00932Y01956D02*
X01009D01*
X00932Y02481D02*
X0102D01*
X03469Y03653D02*
Y03661D01*
X03242Y03659D02*
X03244Y03661D01*
X03242Y03598D02*
Y03659D01*
X03239Y03596D02*
X03242Y03598D01*
X03529Y03481D02*
X0353Y03479D01*
X0268Y03661D02*
X02719D01*
X02679Y03661D02*
X0268Y03661D01*
X03701Y03752D02*
Y03786D01*
X03699Y03751D02*
X03701Y03752D01*
Y03837D02*
Y03861D01*
X03699Y03836D02*
X03701Y03837D01*
X03724Y01674D02*
X03724Y01675D01*
X06339Y03151D02*
X06341Y03152D01*
X06388*
X04707Y04121D02*
X04712Y04115D01*
X04754*
X05267Y04088D02*
Y04126D01*
X03772Y03683D02*
X03794D01*
X03871Y03758D02*
Y04023D01*
X03794Y03683D02*
X03799Y03687D01*
X038*
X03871Y03758*
X03964Y03683D02*
X03987D01*
X03902Y03743D02*
Y04023D01*
X0396Y03687D02*
X03964Y03683D01*
X03958Y03687D02*
X0396D01*
X03902Y03743D02*
X03958Y03687D01*
X03Y03701D02*
X03035Y03666D01*
X03044*
X0601Y02338D02*
X0604Y02369D01*
X06004Y02338D02*
X0601D01*
X0604Y02369D02*
X06056D01*
X06064Y02377*
X06459Y0315D02*
X0646Y0315D01*
Y03164*
X06469Y03173*
X06489*
X0644Y0315D02*
Y0319D01*
X06439Y03191D02*
X0644Y0319D01*
X06354Y03331D02*
X06356Y03329D01*
X06388*
X0642Y03332D02*
X06421Y03331D01*
Y03314D02*
Y03331D01*
Y03314D02*
X06444Y03291D01*
X06409Y03371D02*
X06424D01*
X0644Y03355*
Y03332D02*
Y03355D01*
X06479Y03425D02*
X06479Y03426D01*
X06509Y03456D02*
X06511Y03454D01*
Y03329D02*
Y03454D01*
X06479Y03332D02*
Y03425D01*
X02839Y03666D02*
X02944D01*
X02834Y03661D02*
X02839Y03666D01*
X03044Y03745D02*
Y03951D01*
X03144Y03666D02*
X03239D01*
X03244Y03661*
X03464Y03666D02*
X03469Y03661D01*
X03667Y03786D02*
X03668D01*
X03667Y03861D02*
X03668D01*
X03618Y03909D02*
X03667Y03861D01*
X03589Y03909D02*
X03618D01*
X03701Y03861D02*
X03702Y03859D01*
X03771*
X03772Y03858*
X03701Y03786D02*
X03702Y03784D01*
X03771*
X03772Y03783*
X00594Y00906D02*
X00932D01*
X00199D02*
X00594D01*
Y01431D02*
X00932D01*
X00199D02*
X00594D01*
Y01956D02*
X00932D01*
X00199D02*
X00594D01*
Y02481D02*
X00932D01*
X00199D02*
X00594D01*
X06939Y01889D02*
X07004D01*
X07009Y01883*
X06832Y01931D02*
X06931D01*
X06939Y01922*
X06832Y02031D02*
X06836D01*
X06843Y02038*
Y02096*
X06749Y02035D02*
Y02088D01*
Y02035D02*
X06804Y01981D01*
X06832*
X06481Y01954D02*
X06519D01*
X06369Y01842D02*
X06481Y01954D01*
X06319Y01842D02*
X06369D01*
X06542Y01931D02*
X06637D01*
X06519Y01953D02*
X06542Y01931D01*
X06519Y01953D02*
Y01954D01*
X06533Y02031D02*
X06637D01*
X06519Y02017D02*
X06533Y02031D01*
X06064Y02344D02*
X06067Y02341D01*
X06157*
X06156Y02171D02*
Y0224D01*
X06157Y02241*
X06352D02*
X06468D01*
X06469Y02239*
X06512Y03072D02*
X06584D01*
X0651Y03071D02*
X06512Y03072D01*
X0651Y03071D02*
Y03076D01*
X0646Y03126D02*
X0651Y03076D01*
X0646Y03126D02*
Y03149D01*
X06459Y0315D02*
X0646Y03149D01*
X01048Y04099D02*
Y04192D01*
X01042Y04093D02*
X01048Y04099D01*
X01249D02*
Y04192D01*
X01243Y04093D02*
X01249Y04099D01*
G54D21*
X02584Y00265D02*
D01*
X02584Y00266*
X02584Y00268*
X02584Y00269*
X02583Y0027*
X02583Y00272*
X02582Y00273*
X02582Y00274*
X02581Y00275*
X0258Y00277*
X02579Y00278*
X02578Y00279*
X02578Y00279*
X02905D02*
D01*
X02905Y00279*
X02905Y00279*
X02905Y00279*
X02905Y00279*
X02905Y00279*
Y00279*
D01*
X02904Y00278*
X02903Y00277*
X02902Y00276*
X02902Y00275*
X02901Y00273*
X029Y00272*
X029Y00271*
X029Y00269*
X02899Y00268*
X02899Y00266*
X02899Y00265*
X02899Y00265*
X02764Y00979D02*
D01*
X02764Y00979*
X02764Y00979*
X02764Y00979*
X02764Y00978*
X02764Y00978*
X02764Y00978*
X02764Y00978*
X02764Y00978*
X02764Y00977*
X02764Y00977*
X02765Y00977*
X02765Y00977*
X02765Y00977*
X02765Y00976*
X02765Y00976*
X02766Y00976*
X02766Y00976*
X02766Y00976*
X02766Y00976*
X02767Y00976*
X02767Y00976*
X02767Y00976*
X02767Y00976*
X02746Y00278D02*
D01*
X02745Y00277*
X02745Y00275*
X02744Y00274*
X02743Y00273*
X02743Y00272*
X02742Y0027*
X02742Y00269*
X02742Y00268*
X02742Y00266*
X02742Y00265*
X02742Y00265*
X02746Y00278D02*
D01*
X02747Y00278*
X02747Y00278*
X02747Y00279*
X02747Y00279*
X02747Y00279*
X02748Y00282D02*
D01*
X02748Y00281*
X02748Y00281*
X02748Y00281*
X027Y0083D02*
D01*
X02701Y00831*
X02702Y00832*
X02702Y00833*
X02703Y00833*
X02703Y00834*
X02704Y00835*
X02704Y00836*
X02704Y00837*
X02704Y00838*
X02705Y00839*
X02705Y0084*
X02705Y00841*
X027Y0083D02*
D01*
X02699Y00829*
X02698Y00827*
X02697Y00826*
X02696Y00824*
X02695Y00823*
X02694Y00821*
X02694Y00819*
X02693Y00817*
X02693Y00815*
X02693Y00814*
X02692Y00812*
X02692Y00811*
X0261Y00259D02*
D01*
X0261Y00257*
X0261Y00255*
X0261Y00253*
X02611Y00251*
X02611Y00249*
X02612Y00248*
X02613Y00246*
X02614Y00244*
X02615Y00243*
X02616Y00241*
X02617Y0024*
X02618Y0024*
X02624Y00225D02*
D01*
X02623Y00227*
X02623Y00228*
X02623Y0023*
X02623Y00231*
X02622Y00232*
X02622Y00234*
X02621Y00235*
X0262Y00236*
X0262Y00237*
X02619Y00238*
X02618Y00239*
X02618Y0024*
X02681Y0083D02*
D01*
X02681Y00831*
X02682Y00832*
X02683Y00833*
X02683Y00833*
X02684Y00834*
X02684Y00835*
X02684Y00836*
X02685Y00837*
X02685Y00838*
X02685Y00839*
X02685Y0084*
X02685Y00841*
X02679Y00828D02*
D01*
X02679Y00828*
X02679Y00828*
X02679Y00828*
X02679Y00828*
X02679Y00828*
D01*
X02677Y00826*
X02674Y00823*
X02673Y00821*
X02671Y00818*
X02669Y00815*
X02668Y00812*
X02667Y00809*
X02666Y00805*
X02665Y00802*
X02665Y00799*
X02665Y00796*
X02665Y00795*
X02882Y00822D02*
D01*
X02882Y0082*
X02882Y00817*
X02883Y00814*
X02883Y00812*
X02884Y00809*
X02885Y00806*
X02886Y00804*
X02888Y00802*
X02889Y00799*
X02891Y00797*
X02893Y00795*
X02893Y00795*
X02862D02*
D01*
X02862Y00795*
X02862Y00795*
X02862Y00795*
X02862Y00795*
X02862Y00795*
X02862Y00795*
X02862Y00795*
X02862Y00795*
X02862Y00796*
X02862Y00796*
X02862Y00796*
X02862Y00796*
X02781Y00274D02*
D01*
X02781Y00275*
X02781Y00275*
X02781Y00276*
X02781Y00276*
X02781Y00277*
X0278Y00277*
X0278Y00277*
X0278Y00278*
X0278Y00278*
X02779Y00279*
X02779Y00279*
X02779Y00279*
X02823Y00803D02*
D01*
X02823Y00802*
X02823Y00802*
X02823Y00801*
X02823Y008*
X02823Y00799*
X02824Y00798*
X02824Y00798*
X02825Y00797*
X02825Y00796*
X02826Y00796*
X02826Y00795*
X02826Y00795*
X02799D02*
D01*
X02799Y00796*
X028Y00796*
X02801Y00797*
X02801Y00798*
X02802Y00799*
X02802Y008*
X02802Y00801*
X02803Y00802*
X02803Y00803*
X02803Y00804*
X02803Y00805*
X02803Y00805*
X0274Y00819D02*
D01*
X02738Y00817*
X02737Y00816*
X02736Y00814*
X02735Y00812*
X02734Y00811*
X02734Y00809*
X02733Y00807*
X02732Y00805*
X02732Y00803*
X02732Y00802*
X02732Y008*
X02732Y00799*
X02759Y00795D02*
D01*
X0276Y00796*
X02761Y00796*
X02761Y00797*
X02762Y00798*
X02762Y00799*
X02763Y008*
X02763Y00801*
X02763Y00802*
X02763Y00803*
X02764Y00804*
X02764Y00805*
X02764Y00805*
X0274Y00819D02*
D01*
X0274Y00819*
X02741Y0082*
X02742Y00821*
X02742Y00822*
X02743Y00823*
X02743Y00824*
X02743Y00824*
X02744Y00825*
X02744Y00826*
X02744Y00827*
X02744Y00828*
X02744Y00829*
X02629Y00818D02*
D01*
X02632Y00821*
X02634Y00824*
X02637Y00827*
X02639Y00831*
X0264Y00834*
X02642Y00838*
X02643Y00841*
X02644Y00845*
X02645Y00849*
X02645Y00853*
X02646Y00856*
X02646Y00857*
X02629Y00818D02*
D01*
X02629Y00818*
X02628Y00817*
X02628Y00816*
X02627Y00815*
X02627Y00815*
X02626Y00814*
X02626Y00813*
X02626Y00812*
X02626Y00811*
X02626Y0081*
X02625Y00809*
X02625Y00809*
X02618Y00826D02*
D01*
X02619Y00828*
X0262Y00829*
X02621Y00831*
X02622Y00833*
X02623Y00834*
X02624Y00836*
X02625Y00838*
X02625Y0084*
X02626Y00842*
X02626Y00844*
X02626Y00846*
X02626Y00846*
X02606Y00815D02*
D01*
X02605Y00813*
X02604Y00812*
X02603Y0081*
X02602Y00809*
X02601Y00807*
X026Y00805*
X02599Y00803*
X02599Y00801*
X02598Y00799*
X02598Y00797*
X02598Y00795*
X02598Y00795*
X02938Y00274D02*
D01*
X02938Y00275*
X02938Y00275*
X02938Y00276*
X02938Y00276*
X02938Y00277*
X02938Y00277*
X02938Y00277*
X02937Y00278*
X02937Y00278*
X02937Y00279*
X02937Y00279*
X02937Y00279*
X0274Y00976D02*
D01*
X0274Y00976*
X0274Y00976*
X02741Y00976*
X02741Y00976*
X02741Y00976*
X02741Y00976*
X02742Y00976*
X02742Y00977*
X02742Y00977*
X02742Y00977*
X02743Y00977*
X02743Y00977*
X02743Y00978*
X02743Y00978*
X02743Y00978*
X02744Y00978*
X02744Y00979*
X02744Y00979*
X02744Y00979*
X02744Y00979*
X02744Y0098*
X02744Y0098*
X02744Y0098*
X02823Y00979D02*
D01*
X02823Y00979*
X02823Y00979*
X02823Y00979*
X02823Y00978*
X02823Y00978*
X02823Y00978*
X02823Y00978*
X02823Y00978*
X02823Y00977*
X02824Y00977*
X02824Y00977*
X02824Y00977*
X02824Y00977*
X02824Y00976*
X02824Y00976*
X02825Y00976*
X02825Y00976*
X02825Y00976*
X02825Y00976*
X02826Y00976*
X02826Y00976*
X02826Y00976*
X02826Y00976*
X02799D02*
D01*
X02799Y00976*
X02799Y00976*
X028Y00976*
X028Y00976*
X028Y00976*
X028Y00976*
X02801Y00976*
X02801Y00977*
X02801Y00977*
X02801Y00977*
X02802Y00977*
X02802Y00977*
X02802Y00978*
X02802Y00978*
X02802Y00978*
X02803Y00978*
X02803Y00979*
X02803Y00979*
X02803Y00979*
X02803Y00979*
X02803Y0098*
X02803Y0098*
X02803Y0098*
X02705Y00979D02*
D01*
X02705Y00979*
X02705Y00979*
X02705Y00979*
X02705Y00978*
X02705Y00978*
X02705Y00978*
X02705Y00978*
X02705Y00978*
X02705Y00977*
X02705Y00977*
X02706Y00977*
X02706Y00977*
X02706Y00977*
X02706Y00976*
X02706Y00976*
X02707Y00976*
X02707Y00976*
X02707Y00976*
X02707Y00976*
X02708Y00976*
X02708Y00976*
X02708Y00976*
X02708Y00976*
X02681D02*
D01*
X02681Y00976*
X02681Y00976*
X02681Y00976*
X02682Y00976*
X02682Y00976*
X02682Y00976*
X02683Y00976*
X02683Y00977*
X02683Y00977*
X02683Y00977*
X02684Y00977*
X02684Y00977*
X02684Y00978*
X02684Y00978*
X02684Y00978*
X02684Y00978*
X02685Y00979*
X02685Y00979*
X02685Y00979*
X02685Y00979*
X02685Y0098*
X02685Y0098*
X02685Y0098*
X02413Y00279D02*
D01*
X02409Y00275*
X02405Y0027*
X02401Y00265*
X02398Y0026*
X02395Y00254*
X02393Y00249*
X02391Y00243*
X0239Y00237*
X02388Y00231*
X02388Y00225*
X02387Y00219*
X02387Y00217*
X02646Y00979D02*
D01*
X02646Y00979*
X02646Y00979*
X02646Y00979*
X02646Y00978*
X02646Y00978*
X02646Y00978*
X02646Y00978*
X02646Y00978*
X02646Y00977*
X02646Y00977*
X02647Y00977*
X02647Y00977*
X02647Y00977*
X02647Y00976*
X02647Y00976*
X02648Y00976*
X02648Y00976*
X02648Y00976*
X02648Y00976*
X02648Y00976*
X02649Y00976*
X02649Y00976*
X02649Y00976*
X02444Y00279D02*
D01*
X02442Y00276*
X02439Y00273*
X02436Y00269*
X02434Y00266*
X02432Y00262*
X02431Y00258*
X02429Y00254*
X02428Y0025*
X02427Y00246*
X02427Y00242*
X02427Y00237*
X02427Y00236*
X02622Y00976D02*
D01*
X02622Y00976*
X02622Y00976*
X02622Y00976*
X02623Y00976*
X02623Y00976*
X02623Y00976*
X02624Y00976*
X02624Y00977*
X02624Y00977*
X02624Y00977*
X02625Y00977*
X02625Y00977*
X02625Y00978*
X02625Y00978*
X02625Y00978*
X02625Y00978*
X02626Y00979*
X02626Y00979*
X02626Y00979*
X02626Y00979*
X02626Y0098*
X02626Y0098*
X02626Y0098*
X02781Y00112D02*
D01*
X02781Y00112*
X02781Y00111*
X02781Y00111*
X02781Y00111*
X02781Y00111*
X02781Y00111*
X02782Y00111*
X02782Y00111*
X02782Y00111*
X02782Y00111*
X02782Y00111*
X02782Y00111*
X02772Y00133D02*
D01*
X02772Y00131*
X02773Y00129*
X02773Y00127*
X02774Y00124*
X02774Y00122*
X02775Y0012*
X02776Y00118*
X02777Y00116*
X02778Y00114*
X0278Y00113*
X02781Y00111*
X02782Y00111*
X02612Y00139D02*
D01*
X02612Y00137*
X02613Y00134*
X02613Y00131*
X02614Y00128*
X02615Y00125*
X02616Y00123*
X02617Y0012*
X02619Y00118*
X0262Y00115*
X02622Y00113*
X02624Y00111*
X02624Y00111*
X02575Y00134D02*
D01*
X02575Y00131*
X02576Y00129*
X02576Y00127*
X02577Y00125*
X02577Y00123*
X02578Y0012*
X02579Y00118*
X0258Y00116*
X02582Y00114*
X02583Y00113*
X02585Y00111*
X02585Y00111*
X02418Y00133D02*
D01*
X02418Y0013*
X02419Y00128*
X02419Y00126*
X0242Y00124*
X0242Y00122*
X02421Y0012*
X02422Y00118*
X02423Y00116*
X02424Y00114*
X02426Y00113*
X02427Y00111*
X02427Y00111*
X0261Y00259D02*
Y00279D01*
X02905Y00279D02*
X02905Y00279D01*
X02899Y00137D02*
Y00265D01*
X02764Y00979D02*
Y01038D01*
X02746Y00278D02*
X02746Y00278D01*
X02747Y00279D02*
X02748Y00281D01*
X02748Y00282D02*
X02748Y00282D01*
X02748Y00282*
X02862Y00796D02*
Y00878D01*
X02764Y00805D02*
Y00878D01*
X02781Y00137D02*
Y00274D01*
X02803Y00805D02*
Y00878D01*
X02742Y00137D02*
Y00265D01*
X02823Y00803D02*
Y00878D01*
X02584Y00137D02*
Y00265D01*
X02899Y00137D02*
D01*
X02705Y00841D02*
Y00878D01*
X02692Y00795D02*
Y00811D01*
X02624Y00137D02*
Y00225D01*
X02685Y00841D02*
Y00878D01*
X02679Y00828D02*
X02681Y0083D01*
X02679Y00828D02*
Y00828D01*
X02882Y00822D02*
Y00878D01*
X02732Y00799D02*
Y00799D01*
X02744Y00829D02*
Y00878D01*
X02732Y00795D02*
Y00799D01*
X02625Y00795D02*
Y00809D01*
X02606Y00815D02*
X02618Y00826D01*
X02646Y00857D02*
Y00878D01*
X02626Y00846D02*
Y00878D01*
X02938Y00137D02*
Y00274D01*
X02744Y0098D02*
Y01038D01*
X02823Y00979D02*
Y01038D01*
X02803D02*
X02803Y01038D01*
X02803Y0098D02*
Y01038D01*
X02705Y00979D02*
Y01038D01*
X02685Y0098D02*
Y01038D01*
X02387Y00137D02*
Y00217D01*
X02646Y00979D02*
Y01038D01*
X02427Y00137D02*
Y00236D01*
X02626Y0098D02*
Y01038D01*
X02742Y00111D02*
X02745Y00113D01*
X0274Y00113D02*
X02742Y00111D01*
X02931Y00118D02*
X02939Y00111D01*
X029D02*
X02907Y00118D01*
G54D24*
X06605Y03129D02*
X06647D01*
X06604Y03129D02*
X06605Y03129D01*
X06487Y03125D02*
X06551D01*
X06479Y03132D02*
X06487Y03125D01*
X06479Y03132D02*
Y03143D01*
X06555Y03129D02*
X06604D01*
X06551Y03125D02*
X06555Y03129D01*
X06479Y03143D02*
X06479Y03143D01*
G54D26*
X02756Y03287D03*
Y03237D03*
Y03187D03*
Y03137D03*
Y03087D03*
Y03037D03*
Y02987D03*
Y02937D03*
X03111Y03287D03*
Y03237D03*
Y03187D03*
Y03137D03*
Y03087D03*
Y03037D03*
Y02987D03*
Y02937D03*
G54D27*
X02271Y04275D03*
G54D28*
X02377Y04275D03*
G54D29*
X02234Y04173D03*
X0243D03*
G54D30*
X02383Y0417D03*
X02358D03*
X02332D03*
X02306D03*
X02281D03*
G54D31*
X02465Y04275D03*
X02199D03*
G54D32*
X04046Y04244D03*
Y04027D03*
X03696D03*
Y04244D03*
G54D33*
X03934Y04023D03*
X03902D03*
X03871D03*
X03839D03*
X03808D03*
G54D34*
X00594Y00906D03*
Y01956D03*
Y02481D03*
Y01431D03*
G54D35*
X00654Y00964D03*
Y00847D03*
Y01897D03*
Y02014D03*
Y02422D03*
Y02539D03*
Y01489D03*
Y01372D03*
G54D36*
X03469Y03661D03*
X03444Y0375D03*
X03495D03*
X02834Y03661D03*
X02809Y0375D03*
X0286D03*
X02719Y03661D03*
X02694Y0375D03*
X02745D03*
X03244Y03661D03*
X03219Y0375D03*
X0327D03*
G54D37*
X01846Y04024D03*
Y04049D03*
Y04074D03*
Y04099D03*
Y04124D03*
Y04149D03*
Y04174D03*
Y04199D03*
X01631Y04024D03*
Y04049D03*
Y04074D03*
Y04099D03*
Y04124D03*
Y04149D03*
Y04174D03*
Y04199D03*
X03987Y03683D03*
Y03708D03*
Y03733D03*
Y03758D03*
Y03783D03*
Y03808D03*
Y03833D03*
Y03858D03*
X03772Y03683D03*
Y03708D03*
Y03733D03*
Y03758D03*
Y03783D03*
Y03808D03*
Y03833D03*
Y03858D03*
G54D38*
X06352Y02241D03*
Y02291D03*
Y02341D03*
Y02391D03*
X06157D03*
Y02341D03*
Y02291D03*
Y02241D03*
X06637Y02031D03*
Y01981D03*
Y01931D03*
Y01881D03*
X06832D03*
Y01931D03*
Y01981D03*
Y02031D03*
G54D39*
X06341Y03701D03*
X06197D03*
X06031D03*
X05887D03*
X06202Y03566D03*
X06346D03*
G54D40*
X06726Y03168D03*
X06943D03*
Y03294D03*
X06726D03*
G54D41*
X03451Y03206D03*
X03392D03*
X03451Y03395D03*
X0351D03*
X03569Y03206D03*
X03333Y03395D03*
Y03206D03*
X0351D03*
X03392Y03395D03*
G54D42*
X03569Y03385D03*
G54D43*
X03438Y03051D03*
Y02892D03*
X03531Y03051D03*
Y02892D03*
G54D44*
X03484Y02892D03*
Y03051D03*
G54D45*
X03444Y02995D03*
Y02948D03*
X03525D03*
Y02995D03*
G54D46*
X03344Y04221D03*
Y03951D03*
X03244Y04221D03*
Y03951D03*
X03144Y04221D03*
Y03951D03*
X03044Y04221D03*
Y03951D03*
X02944Y04221D03*
Y03951D03*
G54D47*
X03349Y03666D03*
Y03745D03*
X02944Y03666D03*
Y03745D03*
X03044Y03666D03*
Y03745D03*
X03144Y03666D03*
Y03745D03*
G54D48*
X03477Y02797D03*
X03532D03*
X06035Y03556D03*
X0609D03*
X0415Y03603D03*
X04204D03*
X06897Y01816D03*
X06842D03*
X06782D03*
X06727D03*
X06367Y02451D03*
X06312D03*
X04167Y03701D03*
X04112D03*
X04652Y04206D03*
X04707D03*
X05212D03*
X05267D03*
X04652Y04121D03*
X04707D03*
X05267Y04126D03*
X05212D03*
G54D49*
X03701Y03786D03*
X03668D03*
X03701Y03861D03*
X03668D03*
G54D50*
X02545Y00137D03*
X02466D03*
X02348D03*
X0282D03*
X01915D03*
X02033D03*
X02663D03*
X02702D03*
X0286D03*
X02978D03*
X0219D03*
X01994D03*
X01954D03*
X03017D03*
X02309D03*
X02112D03*
X02151D03*
X02387D03*
X02427D03*
X02584D03*
X02624D03*
X02742D03*
X02781D03*
X02899D03*
X02938D03*
X02505D03*
X02072D03*
X01797D03*
X01836D03*
X01875D03*
X03096D03*
G54D51*
X03057Y00157D03*
G54D52*
X04957Y04206D03*
X05091D03*
X04432D03*
X04566D03*
G54D53*
X04068Y01599D03*
X03911D03*
Y01619D03*
X04068D03*
X03911Y01639D03*
X04068D03*
X03911Y01659D03*
X04068D03*
X03911Y01679D03*
X04068D03*
X03911Y01699D03*
X04068D03*
X03911Y01719D03*
X04068D03*
X03911Y01739D03*
X04068D03*
X03911Y01759D03*
X04068D03*
X03911Y01779D03*
X04068D03*
G54D54*
X06511Y03191D03*
Y03172D03*
Y03211D03*
Y03231D03*
Y0325D03*
Y0327D03*
Y0329D03*
Y03309D03*
Y03329D03*
X06388D03*
Y03309D03*
Y0329D03*
Y0327D03*
Y0325D03*
Y03231D03*
Y03211D03*
Y03191D03*
Y03172D03*
Y03152D03*
X06511D03*
G54D55*
X06479Y03332D03*
X06459D03*
X0644D03*
X0642D03*
Y0315D03*
X0644D03*
X06459D03*
X06479D03*
G54D56*
X00901Y00718D03*
X0096D03*
X00908Y02284D03*
X00967D03*
X009Y01747D03*
X00959D03*
X00904Y01224D03*
X00963D03*
G54D57*
X04149Y02789D03*
Y02842D03*
X04434Y02789D03*
Y02842D03*
G54D58*
X06679Y0242D03*
Y02802D03*
X06319Y01842D03*
Y0146D03*
G54D59*
X04909Y03961D03*
Y02808D03*
G54D60*
X01157Y00906D03*
X00932D03*
Y01956D03*
X01157D03*
X00932Y02481D03*
X01157D03*
Y01431D03*
X00932D03*
G54D61*
X01249Y04254D03*
Y04197D03*
X03589Y03852D03*
Y03909D03*
Y03784D03*
Y03727D03*
X00644Y04197D03*
Y04254D03*
X00846Y04197D03*
Y04254D03*
X01048D03*
Y04197D03*
G54D62*
X04339Y0278D03*
Y02851D03*
X06334Y0211D03*
Y02181D03*
X06659Y02166D03*
Y02095D03*
X06253Y02826D03*
Y02755D03*
X06372Y02826D03*
Y02755D03*
X04104Y0377D03*
Y03841D03*
X02209Y03716D03*
Y03645D03*
X02639Y03535D03*
Y03606D03*
X03693Y03188D03*
Y03117D03*
X04064Y0278D03*
Y02851D03*
X03959Y0278D03*
Y02851D03*
X04234Y0278D03*
Y02851D03*
G54D63*
X04039Y03029D03*
Y03092D03*
X06469Y02239D03*
Y02302D03*
X06519Y01954D03*
Y02017D03*
X04194Y03774D03*
Y03837D03*
X03688Y03266D03*
Y03329D03*
X06604Y03264D03*
Y03327D03*
Y03192D03*
Y03129D03*
G54D64*
X04109Y03044D03*
Y03077D03*
X06939Y01889D03*
Y01922D03*
X06064Y02344D03*
Y02377D03*
X06584Y03039D03*
Y03072D03*
X02139Y03697D03*
Y03664D03*
X02724Y03559D03*
Y03592D03*
X03769Y03234D03*
Y03201D03*
X04454Y03044D03*
Y03077D03*
X04394Y03044D03*
Y03077D03*
X04334Y03044D03*
Y03077D03*
X04274Y03044D03*
Y03077D03*
X04219Y03044D03*
Y03077D03*
X04164Y03044D03*
Y03077D03*
G54D65*
X03269Y02834D03*
Y02814D03*
Y02795D03*
X03209D03*
Y02814D03*
Y02834D03*
G54D66*
X03249Y02784D03*
X03229D03*
Y02845D03*
X03249D03*
G54D67*
X03492Y01398D03*
Y01378D03*
Y01457D03*
Y01477D03*
Y01772D03*
Y01496D03*
Y01792D03*
Y0189D03*
Y01851D03*
Y0187D03*
Y01831D03*
X03651Y0187D03*
Y0189D03*
Y01929D03*
X03492Y01339D03*
Y01359D03*
X03651Y01792D03*
Y01772D03*
Y01851D03*
Y01831D03*
Y01949D03*
Y01988D03*
Y01969D03*
X03492Y01988D03*
Y01969D03*
X03651Y01693D03*
X03492Y01634D03*
Y01673D03*
Y01654D03*
Y01693D03*
X03651Y01733D03*
Y01752D03*
Y01654D03*
Y01575D03*
Y01555D03*
Y01673D03*
Y01634D03*
X03492Y01929D03*
Y01555D03*
Y02008D03*
Y0191D03*
Y01811D03*
Y01713D03*
Y01614D03*
Y01516D03*
Y01418D03*
X03651Y02008D03*
Y0191D03*
Y01811D03*
Y01713D03*
Y01614D03*
Y01516D03*
Y01418D03*
X03492Y01949D03*
X03651Y01595D03*
X03492Y01536D03*
X03651Y01496D03*
Y01477D03*
Y01457D03*
Y01437D03*
Y01398D03*
Y01378D03*
Y01359D03*
Y01339D03*
X03492Y01319D03*
X03651D03*
X03492Y01733D03*
Y01752D03*
X03651Y01536D03*
X03492Y01575D03*
Y01595D03*
Y01437D03*
Y02087D03*
Y02067D03*
Y02047D03*
Y02028D03*
X03651Y02087D03*
Y02067D03*
Y02047D03*
Y02028D03*
X01776Y01634D03*
Y01614D03*
Y0187D03*
Y02028D03*
Y0191D03*
Y01831D03*
Y01949D03*
Y01733D03*
Y01772D03*
X01617Y01929D03*
Y01851D03*
Y0191D03*
Y02028D03*
X01776Y02008D03*
Y01969D03*
Y01457D03*
Y01674D03*
X01617Y0187D03*
Y01969D03*
X01776Y01929D03*
Y01851D03*
Y01811D03*
Y01654D03*
X01617Y02008D03*
X01776Y01752D03*
Y01713D03*
X01617Y01949D03*
X01776Y01555D03*
Y01575D03*
X01617Y01516D03*
Y01457D03*
Y01811D03*
Y01831D03*
X01776Y01437D03*
X01617Y01359D03*
X01776Y01339D03*
X01617Y01575D03*
Y01437D03*
Y01536D03*
Y01555D03*
Y01614D03*
Y01733D03*
Y01674D03*
Y01378D03*
Y01477D03*
Y01418D03*
Y01752D03*
X01776Y01359D03*
X01617Y01339D03*
Y01634D03*
Y01772D03*
X01776Y01378D03*
Y01319D03*
Y01418D03*
X01617Y01319D03*
X01776Y01477D03*
X01617Y01713D03*
Y01654D03*
X01776Y01516D03*
X01617Y02048D03*
X01776D03*
Y01398D03*
Y01496D03*
Y01595D03*
Y01693D03*
Y01792D03*
Y0189D03*
Y01988D03*
X01617Y01398D03*
Y01496D03*
Y01595D03*
Y01693D03*
Y01792D03*
Y0189D03*
Y01988D03*
Y02087D03*
X01776D03*
Y02067D03*
Y01536D03*
X01617Y02067D03*
G54D68*
X03571Y02131D03*
Y01275D03*
X01696Y01275D03*
Y02131D03*
G54D69*
X0298Y02518D03*
Y02358D03*
X02882Y02518D03*
X02783D03*
X02685D03*
X02586D03*
X02488D03*
X0239D03*
X02291D03*
X02882Y02358D03*
X02783D03*
X02685D03*
X02586D03*
X02488D03*
X0239D03*
X02291D03*
X02941D03*
X02961D03*
X02901D03*
X02921D03*
X02842D03*
X02862D03*
X02803D03*
X02823D03*
X02744D03*
X02764D03*
X02705D03*
X02724D03*
X02646D03*
X02665D03*
X02606D03*
X02626D03*
X02547D03*
X02567D03*
X02508D03*
X02527D03*
X02449D03*
X02468D03*
X02409D03*
X02429D03*
X0235D03*
X0237D03*
X02212Y02518D03*
X02232D03*
Y02358D03*
X02212D03*
X02252Y02518D03*
X02272D03*
X02409D03*
X02429D03*
X0235D03*
X0237D03*
X02508D03*
X02527D03*
X02449D03*
X02468D03*
X02606D03*
X02547D03*
X02626D03*
X02567D03*
X02705D03*
X02724D03*
X02646D03*
X02665D03*
X02803D03*
X02823D03*
X02744D03*
X02764D03*
X02901D03*
X02921D03*
X02842D03*
X02862D03*
X02941D03*
X02961D03*
X02252Y02358D03*
X02311D03*
X02331D03*
X02272D03*
X02311Y02518D03*
X02331D03*
X02803Y01038D03*
X02823D03*
X02862Y00878D03*
X02882D03*
X02744D03*
X02764D03*
X02685Y01038D03*
X02705D03*
X02587Y00878D03*
Y01038D03*
X02646Y00878D03*
X02626D03*
X02744Y01038D03*
X02764D03*
X02803Y00878D03*
X02823D03*
X02685D03*
X02705D03*
X02626Y01038D03*
X02646D03*
X02232Y00878D03*
X02429D03*
X0237D03*
X0235D03*
X02331D03*
X02291D03*
X0239D03*
X02488D03*
X02527D03*
X02547D03*
X02567D03*
X02449D03*
X02468D03*
X02252D03*
X02272D03*
X02567Y01038D03*
X0237D03*
X0239D03*
X02429D03*
X02468D03*
X02488D03*
X02449D03*
X02291D03*
X02272D03*
X02252D03*
X02232D03*
X0235D03*
X02331D03*
X02547D03*
X02527D03*
X02862D03*
X02882D03*
X02921Y00878D03*
Y01038D03*
X02941Y00878D03*
Y01038D03*
X0298Y00878D03*
Y01038D03*
X02961D03*
Y00878D03*
X02901Y01038D03*
X02842D03*
X02783D03*
X02724D03*
X02665D03*
X02606D03*
X02508D03*
X02409D03*
X02311D03*
X02901Y00878D03*
X02842D03*
X02783D03*
X02724D03*
X02665D03*
X02606D03*
X02508D03*
X02409D03*
X02311D03*
X02212D03*
Y01038D03*
G54D70*
X02168Y02438D03*
X02168Y00958D03*
X03024D03*
X03024Y02438D03*
G54D71*
X05741Y03361D03*
X05812D03*
X06629Y01421D03*
X067D03*
X06629Y01531D03*
X067D03*
X06439Y03071D03*
X0651D03*
X0373Y00726D03*
X03659D03*
X01802Y04276D03*
X01873D03*
X0428Y03246D03*
X04209D03*
G54D72*
X05634Y03359D03*
X05668D03*
X06327Y02656D03*
X06361D03*
X06327Y02501D03*
X06361D03*
X06327Y02556D03*
X06361D03*
X06327Y02611D03*
X06361D03*
X06676Y01611D03*
X06642D03*
X06676Y01671D03*
X06642D03*
X06676Y01721D03*
X06642D03*
X06676Y01776D03*
X06642D03*
X03716Y00636D03*
X03682D03*
G54D73*
X06906Y02096D03*
X06843D03*
X06093Y02171D03*
X06156D03*
X01664Y04273D03*
X01727D03*
G54D74*
X04275Y03603D03*
X04332D03*
G54D75*
X06749Y02143D03*
Y02088D03*
X06234Y02183D03*
Y02128D03*
X07009Y01883D03*
Y01938D03*
X06004Y02393D03*
Y02338D03*
X02146Y02624D03*
Y02679D03*
X00638Y04038D03*
Y04093D03*
X0084D03*
Y04038D03*
X01042Y04093D03*
Y04038D03*
X01243Y04093D03*
Y04038D03*
X06122Y02488D03*
Y02433D03*
X01933Y04074D03*
Y04129D03*
G54D76*
X02503Y00607D03*
Y00573D03*
X03055Y00607D03*
Y00573D03*
G54D77*
X02334Y03404D03*
Y03483D03*
Y03562D03*
Y0364D03*
X02509Y03404D03*
Y03562D03*
Y03483D03*
Y0364D03*
G54D78*
X01346Y04082D03*
Y04141D03*
Y04037D03*
Y03978D03*
X02151Y04015D03*
Y04074D03*
X02212Y04015D03*
Y04074D03*
X02387Y02899D03*
Y02958D03*
G54D143*
X00299Y01006D03*
Y00806D03*
X00099D03*
Y01006D03*
X00299Y02581D03*
Y02381D03*
X00099D03*
Y02581D03*
X00299Y02056D03*
Y01856D03*
X00099D03*
Y02056D03*
X00299Y01531D03*
Y01331D03*
X00099D03*
Y01531D03*
G54D150*
X00285Y04152D03*
Y00368D03*
G54D153*
X02974Y00224D02*
D01*
X02974Y00226*
X02974Y00227*
X02974Y00228*
X02973Y0023*
X02973Y00231*
X02972Y00232*
X02972Y00234*
X02971Y00235*
X0297Y00236*
X02969Y00237*
X02969Y00237*
X02467Y00217D02*
D01*
X02467Y00218*
X02467Y0022*
X02466Y00221*
X02466Y00222*
X02466Y00224*
X02465Y00225*
X02464Y00226*
X02464Y00227*
X02463Y00229*
X02462Y0023*
X02461Y00231*
X0246Y00232*
X02459Y00233*
X02459Y00233*
X02957Y00251D02*
X02969Y00237D01*
X02974Y00141D02*
Y00224D01*
D01*
X02467Y00111D02*
Y00217D01*
D01*
X02447Y00242D02*
X02459Y00233D01*
X03097Y00111D02*
X03097Y00111D01*
Y00251*
X02636Y00247D02*
X0269D01*
X02637Y00247D02*
X02651D01*
X02636Y00247D02*
X02637Y00247D01*
X02702Y0018D02*
X02703Y00179D01*
X0269Y00247D02*
X02702Y00236D01*
X02703Y00111D02*
Y00179D01*
X02975Y00141D02*
X02978Y00137D01*
X02974Y00141D02*
X02975Y00141D01*
X06346Y03566D02*
X06381D01*
X06414Y03599*
Y03726*
X06565Y03802D02*
X06569Y03806D01*
X0649Y03802D02*
X06565D01*
X06414Y03726D02*
X0649Y03802D01*
X02545Y00244D02*
X02546Y00244D01*
X02545Y00111D02*
Y00244D01*
X01815Y00257D02*
X01835D01*
X02856Y00141D02*
Y00233D01*
X02347Y00112D02*
X02349Y00111D01*
X02837Y00251D02*
X02856Y00233D01*
X02347Y00112D02*
Y00237D01*
X02034Y00111D02*
Y00245D01*
X02817Y00141D02*
X0282Y00137D01*
X02817Y00141D02*
Y00233D01*
X02338Y00246D02*
X02347Y00237D01*
X02651Y00247D02*
X02663Y00235D01*
X02702Y00138D02*
X02702Y00137D01*
X02702Y00138D02*
Y0018D01*
X02663Y00137D02*
Y00235D01*
X02034Y00245D02*
X02034Y00246D01*
X02309D02*
X02338D01*
X02857Y00141D02*
X0286Y00137D01*
X02856Y00141D02*
X02857Y00141D01*
X02799Y00251D02*
X02837D01*
X02702Y0018D02*
Y00236D01*
X02799Y00251D02*
X02817Y00233D01*
X01915Y00111D02*
Y00244D01*
Y00111D02*
X01916Y00111D01*
X02073D02*
X02076Y00114D01*
X03466Y03806D02*
X03539D01*
X03444Y0375D02*
Y03783D01*
X03466Y03806*
X03589Y03784D02*
Y03827D01*
X0354Y03806D02*
X03569D01*
X03589Y03827*
Y03852*
X0354Y03806D02*
X0354Y03806D01*
X03539Y03806D02*
X0354Y03806D01*
Y03715D02*
Y03806D01*
X03219Y0375D02*
Y03826D01*
X0354Y03715D02*
X03654Y03601D01*
X04331Y03604D02*
X04332Y03603D01*
X04331Y03604D02*
Y03631D01*
X0431Y03653D02*
X04331Y03631D01*
X04057Y03601D02*
X04109Y03653D01*
X0431*
X03654Y03601D02*
X04057D01*
X04332Y03603D02*
X04677D01*
X04768Y03511*
X05274*
X02321Y03397D02*
X02329Y03406D01*
X02321Y03361D02*
Y03397D01*
X05274Y03511D02*
X05274Y03511D01*
X0588Y03701D02*
X05887Y03708D01*
X05722Y03783D02*
Y03844D01*
X06094Y03554D02*
Y03565D01*
X05725Y04033D02*
X05829Y04137D01*
X05812Y03302D02*
X05847D01*
X05655D02*
X05812D01*
X05636Y0332D02*
Y03357D01*
Y0332D02*
X05655Y03302D01*
X05636Y03357D02*
X05636Y03357D01*
X06744Y02143D02*
X0675Y02148D01*
X06293Y02181D02*
X06424D01*
X05994Y03449D02*
Y03552D01*
X05847Y03302D02*
X05994Y03449D01*
X062Y03568D02*
X06202Y03566D01*
X062Y03568D02*
Y03586D01*
X06197Y03588D02*
Y03701D01*
Y03588D02*
X062Y03586D01*
X06734Y03806D02*
X069D01*
X06569D02*
X06734D01*
X02084Y00271D02*
X02112D01*
X02072Y00259D02*
X02084Y00271D01*
X02072Y00137D02*
Y00259D01*
X01876Y00111D02*
Y0024D01*
X01846Y00267D02*
X01849D01*
X01837Y00111D02*
Y00255D01*
X01798Y00111D02*
Y00239D01*
X01815Y00257*
X01837Y00255D02*
X01849Y00267D01*
X01835Y00257D02*
X01846Y00267D01*
X06364Y0133D02*
X06667D01*
X06319Y01375D02*
X06364Y0133D01*
X06319Y01375D02*
Y0146D01*
X067Y01363D02*
Y01421D01*
X06667Y0133D02*
X067Y01363D01*
X06712Y02001D02*
Y02114D01*
X06691Y01981D02*
X06712Y02001D01*
X06637Y01981D02*
X06691D01*
X06712Y02135D02*
X0672Y02143D01*
X06712Y02114D02*
Y02135D01*
X067Y02102D02*
X06712Y02114D01*
X06666Y02102D02*
X067D01*
X06659Y02095D02*
X06666Y02102D01*
X0672Y02143D02*
X06744D01*
X06749*
X0671Y0222D02*
X0675Y02181D01*
Y02148D02*
Y02181D01*
X06587Y0222D02*
X0671D01*
X06547Y02181D02*
X06587Y0222D01*
X06281Y02149D02*
Y02192D01*
X06264Y02133D02*
X06281Y02149D01*
X06239Y02133D02*
X06264D01*
X06234Y02128D02*
X06239Y02133D01*
X06281Y02192D02*
X06293Y02181D01*
X06281Y02192D02*
Y02271D01*
X063Y02291*
X06352*
X06372Y02826D02*
Y02909D01*
X06253Y02826D02*
Y02909D01*
X0649Y02791D02*
X06669D01*
X06454Y02755D02*
X0649Y02791D01*
X06372Y02755D02*
X06454D01*
X06669Y02791D02*
X06679Y02802D01*
X06253Y02755D02*
X06372D01*
X06253Y02673D02*
Y02755D01*
X06271Y02656D02*
X06327D01*
X06253Y02673D02*
X06271Y02656D01*
X06199Y02501D02*
X06284D01*
X06187Y02488D02*
X06199Y02501D01*
X06122Y02488D02*
X06187D01*
X06549Y02929D02*
X06639D01*
X0651Y02968D02*
X06549Y02929D01*
X0651Y02968D02*
Y03071D01*
X06679Y02802D02*
Y02889D01*
X06639Y02929D02*
X06679Y02889D01*
X062Y03708D02*
X06226D01*
X06197Y03705D02*
X062Y03708D01*
X06197Y03701D02*
Y03705D01*
X06226Y03708D02*
X06253Y03736D01*
Y0409*
X06207Y04137D02*
X06253Y0409D01*
X05829Y04137D02*
X06207D01*
X06094Y03554D02*
X0615D01*
X06162Y03566*
X06202*
X06119Y03743D02*
Y03819D01*
X06077Y03701D02*
X06119Y03743D01*
X06031Y03701D02*
X06077D01*
X05804D02*
X0588D01*
X05722Y03783D02*
X05804Y03701D01*
X05299Y03537D02*
Y04196D01*
X05289Y04206D02*
X05299Y04196D01*
X05267Y04206D02*
X05289D01*
X05267D02*
Y04255D01*
X05246Y04276D02*
X05267Y04255D01*
X04777Y04276D02*
X05246D01*
X04334Y03044D02*
X04394D01*
X04274D02*
X04334D01*
X04164D02*
X04219D01*
X04109D02*
X04164D01*
X04074Y02842D02*
X04149D01*
X04064Y02851D02*
X04074Y02842D01*
X04149Y02789D02*
X0415Y0279D01*
X04176*
X04187Y02801*
Y0282*
X04206Y02838*
X04222*
X04234Y02851*
X04339D02*
X04391D01*
X04401Y02842*
X04434*
X05887Y03701D02*
Y03708D01*
X05998Y03556D02*
X06035D01*
X05994Y03552D02*
X05998Y03556D01*
X0609Y03561D02*
X06094Y03565D01*
X0609Y03556D02*
Y03561D01*
X04234Y02851D02*
X04339D01*
X02724Y03521D02*
Y03559D01*
X02674Y03501D02*
Y03506D01*
X02639Y03535D02*
X02645D01*
X02674Y03506*
X04234Y02725D02*
Y0278D01*
X04339Y02725D02*
Y0278D01*
X04394Y03044D02*
X04454D01*
X04219D02*
X04274D01*
X03812Y03291D02*
X03969Y03133D01*
X02139Y03663D02*
Y03664D01*
Y03611D02*
Y03663D01*
X02209Y03645D02*
X02211Y03643D01*
X02328*
X02329Y03642*
X02139Y03663D02*
X02157Y03645D01*
X02209*
X01249Y04254D02*
X01293D01*
X01294Y04256*
X03969Y03098D02*
X04029Y03039D01*
X04031*
X04039Y0303*
X03732Y03291D02*
X03812D01*
X03702Y03261D02*
X03732Y03291D01*
X04039Y03029D02*
Y0303D01*
X03969Y03098D02*
Y03133D01*
X04454Y03044D02*
X04457Y03046D01*
X04474*
X04539Y03111*
X04449Y03246D02*
X04539Y03156D01*
X0428Y03246D02*
X04449D01*
X04039Y03029D02*
X04096D01*
X04109Y03043*
Y03044*
X03959Y02851D02*
Y02948D01*
X04039Y03028*
Y03029*
X03959Y02851D02*
X04064D01*
X04434Y02789D02*
X04503D01*
X05274Y03512D02*
X05299Y03537D01*
X05274Y03511D02*
Y03512D01*
X04707Y04206D02*
Y04211D01*
X04711Y04215*
X04716*
X04777Y04276*
X06284Y02501D02*
X06327D01*
X02724Y03592D02*
X02727Y0359D01*
X0275*
X02774Y03566*
X02633Y03606D02*
X02639D01*
X02598Y03642D02*
X02633Y03606D01*
X02504Y03642D02*
X02598D01*
X02659Y03592D02*
X02724D01*
X02645Y03606D02*
X02659Y03592D01*
X02639Y03606D02*
X02645D01*
X04194Y03774D02*
X04253D01*
X04254Y03776*
X04194Y03728D02*
Y03774D01*
X04176Y0371D02*
X04194Y03728D01*
X04171Y0371D02*
X04176D01*
X04167Y03706D02*
X04171Y0371D01*
X04167Y03701D02*
Y03706D01*
X04104Y0377D02*
X04106Y03772D01*
X04192*
X04194Y03774*
X06842Y0181D02*
Y01816D01*
Y01668D02*
Y0181D01*
X06844Y01661D02*
Y01666D01*
X06842Y01668D02*
X06844Y01666D01*
X06424Y02181D02*
X06547D01*
X06424Y02181D02*
X06424Y02181D01*
X02139Y03664D02*
X02142Y03666D01*
X01048Y04254D02*
X01249D01*
X00846D02*
X01048D01*
X00644D02*
X00846D01*
X03189Y03855D02*
Y04101D01*
Y03855D02*
X03219Y03826D01*
X03144Y04146D02*
Y04221D01*
Y04146D02*
X03189Y04101D01*
X02694Y0375D02*
Y03757D01*
X02722Y03786*
X02781*
X02809Y03757*
Y0375D02*
Y03757D01*
X03044Y04221D02*
X03144D01*
X06327Y02611D02*
Y02656D01*
Y02556D02*
Y02611D01*
Y02501D02*
Y02556D01*
X06294Y03701D02*
X06341D01*
X06676Y01776D02*
X06808D01*
X06842Y0181*
X06676Y01721D02*
Y01776D01*
Y01671D02*
Y01721D01*
Y01611D02*
Y01671D01*
X067Y01531D02*
Y01536D01*
X06676Y0156D02*
X067Y01536D01*
X06676Y0156D02*
Y01611D01*
X067Y01421D02*
Y01531D01*
G54D154*
X03987Y03758D02*
X03987Y03758D01*
X04092*
X04104Y0377*
G54D155*
X02112Y00269D03*
G54D156*
X01836Y00269D03*
G54D157*
X03958Y04126D03*
X03784D03*
G54D158*
X03294Y04086D03*
X02994D03*
G54D159*
X05327Y02307D03*
X05127D03*
X04927D03*
X04727D03*
X04927Y01007D03*
X05127D03*
X04327Y02307D03*
X05327Y01007D03*
G54D160*
X04327Y01007D03*
G54D161*
X05578Y0089D03*
Y01689D03*
Y02489D03*
X03979D03*
Y0089D03*
X04062Y02595D03*
X0418D03*
X04298D03*
G54D162*
X05723Y04025D03*
Y03844D03*
X069Y03806D03*
Y03589D03*
X06734D03*
Y03806D03*
X06569Y03589D03*
Y03806D03*
G54D163*
X05934Y03937D03*
G54D164*
X06119Y04056D03*
G54D165*
X06119Y03819D03*
G54D166*
X00199Y00906D03*
Y02481D03*
Y01956D03*
Y01431D03*
G54D167*
X03571Y02097D03*
Y01309D03*
X02203Y02438D03*
X01696Y01309D03*
Y02097D03*
X02203Y00958D03*
X0299D03*
X0299Y02438D03*
G54D168*
X02043Y04157D03*
Y04057D03*
X01457Y04153D03*
Y04053D03*
G54D169*
X02043Y04257D03*
X01457Y04253D03*
G54D170*
X069Y04093D03*
X06569D03*
G54D171*
X02494Y02661D03*
X02692Y02721D03*
X02511Y00405D03*
X0261Y00279D03*
X02578D03*
X0298Y00409D03*
X02821Y00407D03*
X02748Y00282D03*
X02469Y0041D03*
X02905Y00279D03*
X02878Y00249D03*
X02692Y00795D03*
X02665D03*
X02854Y00405D03*
X02779Y00279D03*
X02665Y00405D03*
X02704D03*
X0235D03*
X02389D03*
X02937Y00279D03*
X02957Y00251D03*
X03019Y00405D03*
X0274Y00976D03*
X02767D03*
X02732Y00795D03*
X02681Y00976D03*
X02708D03*
X02447Y00242D03*
X02413Y00279D03*
X02444D03*
X02606Y00931D03*
X02625Y00795D03*
X02598D03*
X02636Y00247D03*
X02799Y00251D03*
X02826Y00976D03*
X02799D03*
X02649D03*
X02622D03*
X02759Y00795D03*
X02799D03*
X02826D03*
X02862D03*
X02893D03*
X02409Y01088D03*
X02311Y0109D03*
X02508Y00931D03*
X02409Y00932D03*
X02724Y01093D03*
X02784Y01094D03*
X02842Y01095D03*
X02546Y00244D03*
X03097Y00251D03*
X02475Y02291D03*
X0233Y02215D03*
X01798Y01304D03*
X02606Y01091D03*
X03554Y01841D03*
X03719Y01996D03*
X03894Y01566D03*
X03379Y01386D03*
X01721Y0189D03*
X01671Y01792D03*
X01674Y01989D03*
X02508Y0109D03*
X03413Y01573D03*
X0167Y01595D03*
X01754Y02126D03*
X02409Y02579D03*
X02586Y02569D03*
X03197Y01714D03*
X03439Y0187D03*
X03298Y01971D03*
X02985Y02287D03*
X02702Y02289D03*
X02821Y02601D03*
X01718Y01792D03*
X02881Y02566D03*
X03732Y01418D03*
X03554Y01891D03*
X02253Y02279D03*
X02272Y02463D03*
X01719Y01536D03*
X02311Y00934D03*
X03571Y02033D03*
X03554Y01991D03*
X02942Y02286D03*
X02841Y02263D03*
X02394Y0272D03*
X01567Y01285D03*
X01675Y01891D03*
X01568Y02067D03*
X02783Y02429D03*
X03719Y01921D03*
X03773Y01666D03*
X02599Y02436D03*
X02494Y02696D03*
X02894Y02431D03*
X02665Y01092D03*
X02475Y02456D03*
X03414Y01805D03*
X03404Y01363D03*
X02579Y02281D03*
X02685Y02311D03*
X0359Y01662D03*
X02404Y02412D03*
X02803Y02307D03*
X01716Y01399D03*
X01721Y01989D03*
X01619Y02121D03*
X03549Y01413D03*
X02488Y02413D03*
X02726Y02293D03*
X01822Y01674D03*
X0167Y01694D03*
X01884Y02071D03*
X02901Y01095D03*
X0292Y02428D03*
X01893Y01693D03*
X03594Y01514D03*
X0245Y02282D03*
X02409Y02314D03*
X02958Y02621D03*
X03406Y01461D03*
X0341Y01713D03*
X03252Y01661D03*
X02933Y00953D03*
X02871Y02297D03*
X02685Y02568D03*
X03571Y02058D03*
X03804Y0184D03*
X01879Y01811D03*
X03554Y01941D03*
X03392Y01871D03*
X03407Y01411D03*
X02575Y02412D03*
X02499Y02236D03*
X02409Y02283D03*
X02783Y02568D03*
X02948Y02456D03*
X03549Y01441D03*
X03718Y01713D03*
X02624Y02461D03*
X01897Y01516D03*
X03834Y01481D03*
X03864Y01511D03*
X03924Y01536D03*
X03719Y01766D03*
X03329Y01826D03*
X02645Y02274D03*
X02665Y02291D03*
X01721Y01694D03*
X01671Y01399D03*
X02581Y02308D03*
X03803Y01691D03*
X03224Y01661D03*
X02252Y02613D03*
X01718Y01497D03*
X01714Y01595D03*
X01671Y01497D03*
X02321Y02586D03*
X03379Y01336D03*
X01797Y00355D03*
X02034Y00246D03*
X01916Y00244D03*
X02309Y00246D03*
X0333Y03301D03*
X0412Y03594D03*
X01393Y01816D03*
X0099Y00687D03*
X04794Y02808D03*
X03183Y03135D03*
X03277Y02963D03*
X03197Y0297D03*
X03491Y03103D03*
X03188Y03187D03*
X0323Y03235D03*
X03358Y03448D03*
X03068Y03395D03*
X02419Y02788D03*
X02146Y02753D03*
X03275Y03141D03*
X03056Y01811D03*
X02413Y03295D03*
X02254Y03536D03*
X02579Y03486D03*
X02389Y03481D03*
X02321Y03361D03*
X02434Y03546D03*
X02634Y03406D03*
X02631Y02876D03*
X02591Y03186D03*
X0259Y03288D03*
X00996Y02256D03*
X02004Y01336D03*
X02028Y01361D03*
X02549Y01755D03*
X02418Y03118D03*
X02414Y03199D03*
X02462Y03172D03*
X02473Y0298D03*
X02146Y04103D03*
X02253Y04086D03*
X01408Y0398D03*
X01345Y04175D03*
X00996Y01187D03*
X00988Y01717D03*
X00937Y02317D03*
X02353Y04017D03*
X01726Y04329D03*
X01788D03*
X04477Y03135D03*
X04064Y02722D03*
X06628Y01372D03*
X04039Y02406D03*
X06974Y01939D03*
X04134Y01651D03*
X03994Y01551D03*
X04134Y01751D03*
X04151Y01623D03*
X03968Y01671D03*
X03969Y01552D03*
X03944Y01816D03*
X04131Y01686D03*
X04179Y01601D03*
X04034Y01546D03*
X03996Y01711D03*
X04064Y01796D03*
Y01511D03*
X03263Y03303D03*
X0396Y02724D03*
X01569Y04171D03*
X02076Y00255D03*
Y00287D03*
X02112D03*
X02151D03*
X02112Y00255D03*
X02151D03*
X01832D03*
X01852D03*
X01872D03*
X01832Y00287D03*
X01852D03*
X01872D03*
X06253Y02909D03*
X06647Y03129D03*
X05267Y04088D03*
X04339Y02725D03*
X04503Y02789D03*
X02231Y02584D03*
X05994Y03552D03*
X04049Y03665D03*
X03829Y03806D03*
X05577Y02214D03*
X02694Y01481D03*
X02384Y01941D03*
X0383Y03762D03*
X06334Y03266D03*
X03744Y03261D03*
X03395Y04222D03*
X04272Y03135D03*
X05634Y02236D03*
X02626Y0177D03*
X06304Y03121D03*
X03939D03*
X02139Y03738D03*
X04208Y03135D03*
X02604Y01734D03*
X06626Y03032D03*
X04152Y03135D03*
X02299Y01916D03*
X02724Y03521D03*
X01248Y02D03*
X02579Y0179D03*
X04068Y03135D03*
X02674Y03501D03*
X04234Y02725D03*
X06456Y03009D03*
X01691Y04079D03*
X03642Y00636D03*
X02259Y03261D03*
X03374Y03273D03*
X03368Y0305D03*
X04039Y03784D03*
X06476Y03231D03*
X04333Y03135D03*
X01557Y04229D03*
X06282Y03226D03*
X03806Y03235D03*
X01261Y02482D03*
X04114Y03135D03*
X06648Y03341D03*
X02888Y04221D03*
X0337Y02888D03*
X02258Y03741D03*
X01749Y0411D03*
X0257Y04283D03*
X01459Y03147D03*
X0144Y03557D03*
X01903Y04018D03*
X0229Y04217D03*
X0388Y03109D03*
X03623Y02587D03*
X03622Y03486D03*
X03491Y03297D03*
X03542Y03319D03*
X03344Y02996D03*
X03744Y03342D03*
X03653Y03293D03*
X03394Y03447D03*
X03436Y03457D03*
X03717Y03072D03*
X02799Y03616D03*
X03589Y01711D03*
X05733Y03556D03*
X05676Y03546D03*
X03603Y00682D03*
X02478Y00937D03*
X06548Y01531D03*
X06602Y01612D03*
Y01672D03*
Y01722D03*
X06601Y01777D03*
X06685Y01828D03*
X06699Y01881D03*
X06949Y02095D03*
X06607Y02176D03*
X06395Y02111D03*
X06048Y02171D03*
X06004Y02434D03*
X06274Y02391D03*
X06398Y02453D03*
X06397Y02501D03*
X06396Y02556D03*
X06397Y0261D03*
X06398Y02657D03*
X06372Y02909D03*
X0491Y04203D03*
X04387Y04206D03*
X03777Y04023D03*
X04085Y03892D03*
X04194Y03884D03*
X04431Y03135D03*
X0286Y03787D03*
X02724Y03729D03*
X03531Y0366D03*
X03269Y03788D03*
X01242Y01472D03*
X01256Y00942D03*
X00654Y0079D03*
X00655Y01028D03*
X00654Y01314D03*
X00653Y01551D03*
X00654Y01839D03*
Y02073D03*
Y02365D03*
X00653Y02593D03*
X02206Y01298D03*
X02205Y032D03*
X02502Y01316D03*
X02525Y02463D03*
X03342Y02263D03*
X03498Y02341D03*
X02429Y02621D03*
X01004Y00906D03*
X02446Y01437D03*
X01008Y0143D03*
X02409Y01967D03*
X01009Y01956D03*
X0102Y02481D03*
X02643Y01616D03*
X02666Y0164D03*
X01884Y03601D03*
X01754Y03661D03*
X03424Y03636D03*
X01549Y03621D03*
X03239Y03596D03*
X01574D03*
X03539Y03806D03*
X03219D03*
X02722Y03786D03*
X02139Y03611D03*
X02084Y03896D03*
X02083Y01411D03*
X02059Y01386D03*
Y03871D03*
X02029Y03836D03*
X01294Y04256D03*
X02004Y03816D03*
X02234Y03506D03*
X03529Y03481D03*
X05274Y03511D03*
X06284Y02501D03*
X02679Y03661D03*
X02774Y03566D03*
X02993Y03751D03*
X03699D03*
X03014Y03831D03*
X03699Y03836D03*
X04254Y03776D03*
X02894Y01561D03*
X02919Y01536D03*
X02274Y01506D03*
X02719Y01591D03*
X03724Y01675D03*
X06844Y01661D03*
X06424Y02181D03*
X06309Y03199D03*
X06339Y03151D03*
X04754Y04115D03*
X01779Y04156D03*
X03504Y04086D03*
X03854Y03151D03*
X03829Y03176D03*
X03799Y03201D03*
X06439Y03191D03*
X06354Y03331D03*
X06444Y03291D03*
X03302Y03344D03*
X06409Y03371D03*
X06447Y03396D03*
X06479Y03426D03*
X06509Y03456D03*
X03469D03*
X01849Y03701D03*
X06294D03*
G54D172*
X02531Y03853D03*
Y0283D03*
X00149D03*
Y03853D03*
M02*